G04 ================== begin FILE IDENTIFICATION RECORD ==================*
G04 Layout Name:  9049_F0T_FAN_BOARD_MP5048_D_v02_20221209_0830.brd*
G04 Film Name:    pmt.art*
G04 File Format:  Gerber RS274X*
G04 File Origin:  Cadence Allegro 17.2-S081*
G04 Origin Date:  Mon Dec 12 15:05:04 2022*
G04 *
G04 Layer:  DRAWING FORMAT/TITLE_BLOCK_A*
G04 Layer:  VIA CLASS/PASTEMASK_TOP*
G04 Layer:  PACKAGE GEOMETRY/PASTEMASK_TOP*
G04 Layer:  DRAWING FORMAT/TITLE_BLOCK*
G04 Layer:  PIN/PASTEMASK_TOP*
G04 Layer:  MANUFACTURING/PHOTOPLOT_OUTLINE*
G04 Layer:  DRAWING FORMAT/TITLE_DATA_PMT*
G04 *
G04 Offset:    (0.00 0.00)*
G04 Mirror:    No*
G04 Mode:      Positive*
G04 Rotation:  0*
G04 FullContactRelief:  No*
G04 UndefLineWidth:     6.00*
G04 ================== end FILE IDENTIFICATION RECORD ====================*
%FSLAX25Y25*MOIN*%
%IR0*IPPOS*OFA0.00000B0.00000*MIA0B0*SFA1.00000B1.00000*%
%ADD40R,.032X.007*%
%ADD11C,.03*%
%ADD38R,.007X.032*%
%ADD15C,.054*%
%ADD44C,.039*%
%ADD18R,.174X.087*%
%ADD16R,.054X.054*%
%AMMACRO23*
4,1,28,-.00748,-.00052,
-.00984,-.00052,
-.00984,-.00603,
-.009782,-.006705,
-.009607,-.007359,
-.009321,-.007974,
-.008933,-.008529,
-.008455,-.009009,
-.0079,-.009398,
-.007286,-.009685,
-.006632,-.009861,
-.005957,-.00992,
-.00591,-.00992,
.00591,-.00992,
.006585,-.009869,
.007242,-.009701,
.007859,-.009421,
.008418,-.009039,
.008903,-.008565,
.009297,-.008015,
.009591,-.007404,
.009773,-.006751,
.00984,-.006077,
.00984,-.00603,
.00984,-.00052,
.00748,-.00052,
.00748,.00991,
-.00748,.00991,
-.00748,-.00052,
0.0*
%
%ADD23MACRO23*%
%AMMACRO14*
4,1,28,-.00052,.00748,
-.00052,.00984,
-.00603,.00984,
-.006705,.009782,
-.007359,.009607,
-.007974,.009321,
-.008529,.008933,
-.009009,.008455,
-.009398,.0079,
-.009685,.007286,
-.009861,.006632,
-.00992,.005957,
-.00992,.00591,
-.00992,-.00591,
-.009869,-.006585,
-.009701,-.007242,
-.009421,-.007859,
-.009039,-.008418,
-.008565,-.008903,
-.008015,-.009297,
-.007404,-.009591,
-.006751,-.009773,
-.006077,-.00984,
-.00603,-.00984,
-.00052,-.00984,
-.00052,-.00748,
.00991,-.00748,
.00991,.00748,
-.00052,.00748,
0.0*
%
%ADD14MACRO14*%
%AMMACRO22*
4,1,28,-.00748,.00051,
-.00984,.00051,
-.00984,.00602,
-.009782,.006695,
-.009607,.007349,
-.009321,.007964,
-.008933,.008519,
-.008455,.008998,
-.0079,.009388,
-.007287,.009675,
-.006632,.009851,
-.005958,.00991,
-.00591,.00991,
.00591,.00991,
.006585,.009859,
.007242,.009691,
.007859,.009411,
.008418,.009029,
.008903,.008555,
.009297,.008005,
.00959,.007394,
.009773,.006742,
.00984,.006068,
.00984,.00602,
.00984,.00051,
.00748,.00051,
.00748,-.00992,
-.00748,-.00992,
-.00748,.00051,
0.0*
%
%ADD22MACRO22*%
%AMMACRO21*
4,1,28,.00051,.00748,
.00051,.00984,
.00602,.00984,
.006695,.009782,
.007349,.009607,
.007964,.009321,
.008519,.008933,
.008998,.008455,
.009388,.0079,
.009675,.007287,
.009851,.006632,
.00991,.005958,
.00991,.00591,
.00991,-.00591,
.009859,-.006585,
.009691,-.007242,
.009411,-.007859,
.009029,-.008418,
.008555,-.008903,
.008005,-.009297,
.007394,-.00959,
.006742,-.009773,
.006068,-.00984,
.00602,-.00984,
.00051,-.00984,
.00051,-.00748,
-.00992,-.00748,
-.00992,.00748,
.00051,.00748,
0.0*
%
%ADD21MACRO21*%
%ADD36R,.02X.016*%
%ADD17R,.05X.04*%
%ADD43R,.016X.02*%
%ADD41R,.024X.022*%
%ADD13R,.04X.05*%
%ADD34R,.032X.024*%
%ADD33R,.022X.024*%
%ADD25R,.036X.011*%
%ADD12R,.02X.018*%
%ADD31R,.024X.032*%
%ADD24R,.011X.036*%
%ADD10R,.018X.02*%
%ADD46C,.4*%
%ADD32R,.032X.034*%
%ADD37R,.032X.028*%
%ADD35R,.028X.032*%
%ADD30R,.068X.022*%
%ADD42R,.036X.028*%
%ADD29R,.059X.014*%
%ADD45R,.014X.059*%
%ADD39R,.107X.107*%
%ADD26R,.109X.109*%
%AMMACRO28*
4,1,28,.00748,.00052,
.00984,.00052,
.00984,.00603,
.009782,.006705,
.009607,.007359,
.009321,.007974,
.008933,.008529,
.008455,.009009,
.0079,.009398,
.007286,.009685,
.006632,.009861,
.005957,.00992,
.00591,.00992,
-.00591,.00992,
-.006585,.009869,
-.007242,.009701,
-.007859,.009421,
-.008418,.009039,
-.008903,.008565,
-.009297,.008015,
-.009591,.007404,
-.009773,.006751,
-.00984,.006077,
-.00984,.00603,
-.00984,.00052,
-.00748,.00052,
-.00748,-.00991,
.00748,-.00991,
.00748,.00052,
0.0*
%
%ADD28MACRO28*%
%AMMACRO20*
4,1,28,.00052,-.00748,
.00052,-.00984,
.00603,-.00984,
.006705,-.009782,
.007359,-.009607,
.007974,-.009321,
.008529,-.008933,
.009009,-.008455,
.009398,-.0079,
.009685,-.007286,
.009861,-.006632,
.00992,-.005957,
.00992,-.00591,
.00992,.00591,
.009869,.006585,
.009701,.007242,
.009421,.007859,
.009039,.008418,
.008565,.008903,
.008015,.009297,
.007404,.009591,
.006751,.009773,
.006077,.00984,
.00603,.00984,
.00052,.00984,
.00052,.00748,
-.00991,.00748,
-.00991,-.00748,
.00052,-.00748,
0.0*
%
%ADD20MACRO20*%
%AMMACRO27*
4,1,28,.00748,-.00051,
.00984,-.00051,
.00984,-.00602,
.009782,-.006695,
.009607,-.007349,
.009321,-.007964,
.008933,-.008519,
.008455,-.008998,
.0079,-.009388,
.007287,-.009675,
.006632,-.009851,
.005958,-.00991,
.00591,-.00991,
-.00591,-.00991,
-.006585,-.009859,
-.007242,-.009691,
-.007859,-.009411,
-.008418,-.009029,
-.008903,-.008555,
-.009297,-.008005,
-.00959,-.007394,
-.009773,-.006742,
-.00984,-.006068,
-.00984,-.00602,
-.00984,-.00051,
-.00748,-.00051,
-.00748,.00992,
.00748,.00992,
.00748,-.00051,
0.0*
%
%ADD27MACRO27*%
%AMMACRO19*
4,1,28,-.00051,-.00748,
-.00051,-.00984,
-.00602,-.00984,
-.006695,-.009782,
-.007349,-.009607,
-.007964,-.009321,
-.008519,-.008933,
-.008998,-.008455,
-.009388,-.0079,
-.009675,-.007287,
-.009851,-.006632,
-.00991,-.005958,
-.00991,-.00591,
-.00991,.00591,
-.009859,.006585,
-.009691,.007242,
-.009411,.007859,
-.009029,.008418,
-.008555,.008903,
-.008005,.009297,
-.007394,.00959,
-.006742,.009773,
-.006068,.00984,
-.00602,.00984,
-.00051,.00984,
-.00051,.00748,
.00992,.00748,
.00992,-.00748,
-.00051,-.00748,
0.0*
%
%ADD19MACRO19*%
%ADD47C,.006*%
G75*
%LPD*%
G75*
G54D10*
X9425Y124000D03*
X12575D03*
X25075D03*
X21925D03*
X16575Y393000D03*
X13425D03*
X15075Y487000D03*
X11925D03*
X27575D03*
X24425D03*
X11925Y491000D03*
X15075D03*
X17075Y1215000D03*
X13925D03*
X53775Y500500D03*
Y495500D03*
Y490500D03*
Y485500D03*
X53850Y480500D03*
X53775Y526000D03*
Y521000D03*
Y516000D03*
Y511000D03*
Y506000D03*
X53850Y536000D03*
X53775Y531000D03*
X54925Y805000D03*
Y816000D03*
Y1168500D03*
Y1156000D03*
Y1160000D03*
Y1178500D03*
X36075Y1235500D03*
X32925D03*
X65425Y81000D03*
X68575D03*
X65425Y98000D03*
X68575D03*
X75075Y406000D03*
X71925D03*
X64925Y427000D03*
X68075D03*
X64925Y443500D03*
X68075D03*
X58425Y475000D03*
X61575D03*
X60075Y500500D03*
X56925D03*
X60075Y495500D03*
X56925D03*
X60075Y490500D03*
X56925D03*
X60075Y485500D03*
X56925D03*
X60150Y480500D03*
X57000D03*
X56925Y500500D03*
Y495500D03*
Y490500D03*
Y485500D03*
X57000Y480500D03*
X60075Y526000D03*
X56925D03*
X60075Y521000D03*
X56925D03*
X60075Y516000D03*
X56925D03*
X60075Y511000D03*
X56925D03*
X60075Y506000D03*
X56925D03*
Y526000D03*
Y521000D03*
Y516000D03*
Y511000D03*
Y506000D03*
X60150Y536000D03*
X57000D03*
X60075Y531000D03*
X56925D03*
X57000Y536000D03*
X56925Y531000D03*
X74075Y746500D03*
X70925D03*
X58075Y805000D03*
Y816000D03*
X71425Y823500D03*
X74575D03*
X64925Y807500D03*
X68075D03*
X66925Y834000D03*
X70075D03*
X75075Y1138500D03*
X71925D03*
X58075Y1168500D03*
Y1156000D03*
Y1160000D03*
X64425Y1168000D03*
X67575D03*
X58075Y1178500D03*
X64425Y1184000D03*
X67575D03*
X72575Y1196500D03*
X69425D03*
X98925Y527000D03*
X120425Y144500D03*
X123575D03*
X124425Y429000D03*
X102075Y527000D03*
X129925Y65000D03*
X133075D03*
X138575Y81000D03*
X135425D03*
X138575Y97000D03*
X135425D03*
X127925Y114000D03*
X131075D03*
X129425Y403728D03*
X132575D03*
X127575Y429000D03*
X139575Y424500D03*
X136425D03*
X128425Y465500D03*
X131575D03*
X147350Y487000D03*
X147425Y492000D03*
Y497000D03*
Y502000D03*
Y507000D03*
Y512000D03*
Y517000D03*
Y522000D03*
Y527000D03*
Y532000D03*
Y537000D03*
X147350Y542000D03*
X128425Y762000D03*
X131575D03*
X148075Y796500D03*
X144925D03*
X148075Y786500D03*
X144925D03*
X139075Y790800D03*
X135925D03*
X128425Y824614D03*
X131575D03*
X145425Y1146400D03*
Y1156000D03*
Y1165000D03*
Y1169500D03*
X139075Y1170000D03*
X135925D03*
X139075Y1154000D03*
X135925D03*
X128425Y1188000D03*
X131575D03*
X150500Y487000D03*
X150575Y492000D03*
Y497000D03*
Y502000D03*
X153650Y487000D03*
X150500D03*
X153725Y492000D03*
X150575D03*
X153725Y497000D03*
X150575D03*
X153725Y502000D03*
X150575D03*
Y507000D03*
Y512000D03*
Y517000D03*
Y522000D03*
X153725Y507000D03*
X150575D03*
X153725Y512000D03*
X150575D03*
X153725Y517000D03*
X150575D03*
X153725Y522000D03*
X150575D03*
Y527000D03*
Y532000D03*
Y537000D03*
X150500Y542000D03*
X153725Y527000D03*
X150575D03*
X153725Y532000D03*
X150575D03*
X153725Y537000D03*
X150575D03*
X153650Y542000D03*
X150500D03*
X148575Y1146400D03*
Y1156000D03*
Y1165000D03*
Y1169500D03*
X190425Y124500D03*
X193575D03*
X177925D03*
X181075D03*
X186925Y490000D03*
X190075D03*
X186425Y1215000D03*
X189575D03*
X178075Y1236500D03*
X174925D03*
G54D20*
X29483Y255500D03*
X22274Y262728D03*
X25483Y251500D03*
X17983Y641000D03*
Y660000D03*
Y654000D03*
Y645500D03*
Y686000D03*
Y680500D03*
Y672500D03*
Y666500D03*
X16483Y715000D03*
Y727000D03*
X22983Y974500D03*
X16983Y1239500D03*
X35774Y263728D03*
X46544Y277728D03*
X52483Y289000D03*
X53983Y641000D03*
Y660000D03*
Y654000D03*
Y647000D03*
Y685000D03*
Y679000D03*
Y672500D03*
Y666500D03*
X37483Y727500D03*
X47044Y1004500D03*
X35774Y990500D03*
X57526Y56342D03*
X57983Y79692D03*
X57526Y401378D03*
X57983Y424728D03*
X71983Y641000D03*
Y657500D03*
Y651500D03*
Y647000D03*
Y685000D03*
Y679000D03*
Y672500D03*
Y666500D03*
X73983Y704000D03*
Y709500D03*
Y719000D03*
Y724000D03*
Y715000D03*
Y742500D03*
Y751500D03*
X57526Y764764D03*
X66483Y778500D03*
X57983Y788114D03*
X59483Y1024000D03*
Y1016000D03*
X57526Y1128650D03*
X57983Y1152000D03*
X91483Y92000D03*
X83483Y676000D03*
Y684000D03*
Y692000D03*
Y700000D03*
X98483Y731000D03*
Y738000D03*
Y745000D03*
X107567Y81551D03*
X101983Y478500D03*
Y483425D03*
Y498500D03*
Y488500D03*
Y517500D03*
X115483Y667500D03*
Y671500D03*
Y675500D03*
Y679500D03*
Y683500D03*
Y687500D03*
X109483Y706500D03*
Y711000D03*
X115483Y693000D03*
X101983Y706500D03*
Y711000D03*
X109483Y731000D03*
Y718000D03*
Y738000D03*
Y745000D03*
X120983Y752000D03*
X139983Y107842D03*
X141483Y126842D03*
X130983Y118000D03*
X145983Y253000D03*
X145965Y262728D03*
X132483Y408000D03*
X131483Y456728D03*
X139983Y451728D03*
X140483Y470728D03*
X132483Y728500D03*
X131483Y820114D03*
X139983Y815114D03*
X140483Y834114D03*
X145965Y992649D03*
X131483Y1183500D03*
X140483Y1197500D03*
X148483Y107842D03*
Y98842D03*
X159465Y263728D03*
X155841Y277728D03*
X161983Y288000D03*
X148483Y442728D03*
Y451728D03*
X166983Y706000D03*
Y733000D03*
X151983Y729000D03*
X148483Y806114D03*
Y815114D03*
X148983Y985000D03*
X155841Y1004500D03*
X159465Y993649D03*
X167983Y1025500D03*
Y1017500D03*
X148483Y1160500D03*
Y1178500D03*
X191483Y515500D03*
Y521000D03*
Y532000D03*
Y526500D03*
X172983Y663500D03*
Y659500D03*
Y651500D03*
X178983Y720000D03*
Y713000D03*
Y747000D03*
Y740000D03*
X189483Y1240500D03*
G54D11*
X9425Y129000D03*
X9400Y241516D03*
X10500Y274500D03*
X11800Y284000D03*
X11433Y983048D03*
X17200Y124000D03*
X25075Y119000D03*
X34544Y192540D03*
X34480Y202243D03*
X29191Y210428D03*
X22170Y246150D03*
X14791Y247715D03*
X29390Y246960D03*
X16873Y257024D03*
X27987Y264636D03*
X21500Y267500D03*
X32716Y273500D03*
X24000Y276000D03*
X18185Y312228D03*
X27185D03*
X17500Y361728D03*
X26500D03*
X29820Y379910D03*
X24880Y480480D03*
X19700Y487000D03*
X21320Y506500D03*
X16580Y526220D03*
X22100Y526120D03*
X21070Y636050D03*
X19850Y691868D03*
X21500Y727000D03*
X22000Y718000D03*
X29000Y728000D03*
X19820Y754600D03*
X27587Y937815D03*
X14791Y976000D03*
X27886Y972134D03*
X23009Y995491D03*
X30522Y1000288D03*
X18185Y1038900D03*
X25000Y1104300D03*
X25060Y1215540D03*
X50000Y63842D03*
X48100Y56342D03*
X48184Y73876D03*
X48313Y68687D03*
X49985Y81177D03*
X49500Y109600D03*
X50000Y97500D03*
X51400Y120342D03*
X36880Y249217D03*
X42309Y251270D03*
X48456Y230214D03*
X41864Y265636D03*
X44500Y272767D03*
X40500Y295500D03*
X51956Y283826D03*
X45500Y298350D03*
X52000Y298528D03*
X57430Y298520D03*
X49800Y401378D03*
X46500Y416000D03*
Y423868D03*
Y432116D03*
X50000Y428000D03*
X49200Y457228D03*
X46500Y451614D03*
Y463378D03*
X48217Y480500D03*
X41196Y489754D03*
X49023Y490500D03*
X45953Y495500D03*
X48872Y500500D03*
X44140Y505060D03*
X48970Y507700D03*
X47140Y512860D03*
X48500Y519850D03*
X49120Y526000D03*
X43450Y528170D03*
X47865Y534580D03*
X54160Y689760D03*
X49400Y772264D03*
X49800Y764764D03*
X47100Y789700D03*
X46500Y783764D03*
X46900Y795128D03*
X48000Y801075D03*
X50900Y826998D03*
X46500Y820614D03*
X46900Y806500D03*
X35259Y968798D03*
X38500Y977199D03*
X40500Y995000D03*
X39061Y1005000D03*
X51852Y1012249D03*
X42000Y1023000D03*
X44100Y1027850D03*
X50000Y1023000D03*
X46500Y1147650D03*
X53900Y1142766D03*
X46409Y1136709D03*
X49400Y1153000D03*
X49764Y1175063D03*
X47000Y1166500D03*
X48200Y1160000D03*
X50900Y1190150D03*
X46500Y1184000D03*
X37200Y1215500D03*
X40700Y1235600D03*
X73877Y80768D03*
X81400Y95000D03*
X67310Y114250D03*
X71689Y302000D03*
X64561Y298446D03*
X76682Y426000D03*
X80650Y457650D03*
X65300Y480500D03*
X68930Y485500D03*
X65300Y490500D03*
X70460Y495120D03*
X64700Y498190D03*
X69290Y500790D03*
X65479Y504809D03*
X64800Y510030D03*
X66290Y515220D03*
X64820Y520300D03*
X64710Y525630D03*
X73500Y521000D03*
X64945Y534505D03*
X61710Y559000D03*
X79930Y579000D03*
X72899Y582500D03*
X80400Y621200D03*
X73285Y616764D03*
X64480Y636220D03*
X72000Y623700D03*
X60500Y693500D03*
X65610Y700000D03*
X60260Y704661D03*
X65920Y708260D03*
X65100Y725200D03*
X65870Y715000D03*
X65087Y747089D03*
X80500Y822500D03*
X72000Y1013500D03*
X74000Y1026000D03*
X66000Y1025000D03*
X64231Y1115268D03*
X80000Y1151500D03*
X79991Y1181260D03*
X93075Y72000D03*
X93312Y132925D03*
X89169Y401350D03*
X93648Y482621D03*
X93477Y490571D03*
X90990Y521240D03*
X92194Y572807D03*
X81442Y573302D03*
X89610Y580015D03*
X99500Y578500D03*
X87977Y623045D03*
X95732Y622114D03*
X101284Y671500D03*
X101124Y715876D03*
X95980Y805970D03*
X81500Y789000D03*
X95920Y813575D03*
X102500Y979500D03*
X82000Y1123500D03*
X97760Y1193780D03*
X112500Y65500D03*
X110425Y114000D03*
X124000Y150630D03*
X115680Y139670D03*
X127482Y312228D03*
X118500Y403500D03*
X110000Y392500D03*
X122100Y418100D03*
X127000Y446000D03*
X122500Y473500D03*
X122070Y495240D03*
X114913Y495488D03*
X106740Y508780D03*
X110000Y526490D03*
X107320Y519640D03*
X109000Y573500D03*
X123603Y575972D03*
X107000Y621000D03*
X115500Y622000D03*
X124323Y621748D03*
X123608Y664209D03*
X124830Y679870D03*
X120400Y670820D03*
X124820Y674220D03*
X120305Y677055D03*
X120550Y689650D03*
X121920Y684380D03*
X112339Y701350D03*
X119975Y723132D03*
X121500Y809000D03*
X122000Y838500D03*
X127182Y1039000D03*
X120300Y1148500D03*
X123000Y1173500D03*
X116737Y1162763D03*
X112281Y1194600D03*
X138700Y57700D03*
X135700Y102300D03*
X128000Y251000D03*
X137495Y248875D03*
X142400Y269800D03*
X133963Y255892D03*
X129370Y495230D03*
X141500Y487500D03*
X136000Y498500D03*
X141390Y496350D03*
X142060Y522960D03*
X133470Y527000D03*
X139020Y514480D03*
X136560Y519360D03*
X135420Y537000D03*
X139890Y542000D03*
X142330Y532000D03*
X131875Y623376D03*
X139350Y694910D03*
X129112Y978769D03*
X136505Y986470D03*
X138605Y977649D03*
X146644Y1007363D03*
X149500Y1023000D03*
X157000Y52982D03*
X156950Y76050D03*
X156782Y87719D03*
X157000Y101000D03*
X153200Y107842D03*
X157000Y93000D03*
X154124Y124576D03*
X156600Y114600D03*
X165164Y189143D03*
X164964Y199543D03*
X164864Y208443D03*
X152500Y249501D03*
X161200Y251200D03*
X159430Y244830D03*
X161128Y283003D03*
X152420Y296500D03*
X167000Y296310D03*
X160777Y275688D03*
X160000Y298500D03*
X154500Y410000D03*
X157496Y400176D03*
X155598Y426934D03*
X155309Y435073D03*
X155686Y418730D03*
X153324Y449248D03*
X157000Y455738D03*
Y442728D03*
Y468500D03*
X152600Y463612D03*
X162220Y505480D03*
X166630Y502000D03*
X159680Y497000D03*
X165300Y492000D03*
X159830Y487000D03*
X158870Y525510D03*
X158410Y516230D03*
X158570Y509929D03*
X159730Y539520D03*
X158790Y533400D03*
X164152Y657373D03*
X165103Y678233D03*
X164572Y669102D03*
X165032Y685986D03*
X161312Y696884D03*
X171087Y724838D03*
X172000Y751500D03*
X173800Y759446D03*
X152266Y773430D03*
X155800Y779425D03*
X156500Y787700D03*
X157000Y801500D03*
X154168Y812669D03*
X155800Y826998D03*
X157000Y819114D03*
X153300Y806114D03*
X156900Y834114D03*
X154502Y971101D03*
X152823Y978573D03*
X160732Y977966D03*
X164337Y1002475D03*
X159500Y1023000D03*
X153150Y1028430D03*
X152600Y1135000D03*
X157000Y1146925D03*
Y1155000D03*
Y1164500D03*
X153200Y1169500D03*
X157000Y1182500D03*
X157500Y1197500D03*
X152600Y1190384D03*
X155286Y1175985D03*
X162800Y1215277D03*
X162400Y1229900D03*
X193575Y129925D03*
X185700Y124500D03*
Y112900D03*
X185358Y230328D03*
X173858Y298500D03*
X183500Y299500D03*
X188800Y408300D03*
X183610Y398050D03*
X185700Y476200D03*
X194000Y550000D03*
X182730Y535090D03*
X183720Y529289D03*
X176350Y540120D03*
X187500Y643500D03*
X180500Y684500D03*
X179000Y676500D03*
X187925Y701000D03*
X181000Y696500D03*
X184425Y738000D03*
X193308Y839608D03*
X177021Y1016322D03*
X182058Y1022519D03*
X173858Y1025500D03*
G54D30*
X30100Y735500D03*
Y740500D03*
Y745500D03*
Y750500D03*
X50900D03*
Y745500D03*
Y740500D03*
Y735500D03*
G54D12*
X8900Y139356D03*
Y142506D03*
X22500Y255425D03*
Y258575D03*
X10600Y862925D03*
Y866075D03*
X17500Y980925D03*
Y984075D03*
X53500Y801075D03*
Y797925D03*
X72500Y70575D03*
Y67425D03*
X59500Y104425D03*
Y107575D03*
Y89425D03*
Y92575D03*
X71500Y127575D03*
Y124425D03*
X56500Y292575D03*
Y289425D03*
X59500Y434925D03*
Y438075D03*
Y448925D03*
Y452075D03*
X72000Y769925D03*
Y773075D03*
X57500Y801075D03*
Y797925D03*
X75500Y846425D03*
Y849575D03*
X63500Y1019575D03*
Y1016425D03*
X87500Y132925D03*
Y136075D03*
X109000Y487425D03*
Y490575D03*
X144500Y71425D03*
Y74575D03*
Y85425D03*
Y88575D03*
X139000Y253925D03*
Y257075D03*
X145000Y432925D03*
X144500Y423075D03*
Y419925D03*
X145000Y436075D03*
Y779425D03*
Y782575D03*
X127000Y801425D03*
Y804575D03*
X142000Y984425D03*
Y987575D03*
X133000Y1128925D03*
Y1132075D03*
X167000Y291575D03*
Y288425D03*
X149000Y779425D03*
Y782575D03*
X179000Y387425D03*
Y390575D03*
X181500Y490075D03*
Y486925D03*
X177500D03*
Y490075D03*
X179000Y857575D03*
Y854425D03*
X172000Y1020575D03*
Y1017425D03*
X194854Y141356D03*
Y144506D03*
X197500Y869425D03*
Y872575D03*
G54D21*
X29484Y259500D03*
X16484Y502000D03*
Y511000D03*
Y515500D03*
Y506500D03*
Y520000D03*
X26984Y641000D03*
Y645500D03*
Y660000D03*
Y654000D03*
Y686000D03*
Y680500D03*
Y672500D03*
Y666500D03*
X12484Y734000D03*
X22984D03*
X16484Y723000D03*
Y719000D03*
X12484Y748000D03*
Y741000D03*
X22984Y748000D03*
Y741000D03*
X24984Y981500D03*
Y985500D03*
X35775Y268728D03*
X52484Y293000D03*
X46545Y282728D03*
X35775Y995500D03*
X47045Y1009500D03*
X58027Y75342D03*
X57984Y84192D03*
X66527Y75342D03*
X60045Y283728D03*
X74984Y410000D03*
X66027Y401378D03*
X57984Y429228D03*
X58027Y420378D03*
X66527D03*
X71984Y475000D03*
X62984Y641000D03*
Y660000D03*
Y655400D03*
Y647000D03*
Y685000D03*
Y679000D03*
Y672500D03*
Y666500D03*
X73984Y729000D03*
Y738500D03*
Y734500D03*
X66027Y764764D03*
X57984Y792614D03*
X58027Y783764D03*
X66527D03*
X76984Y834000D03*
X60545Y1010500D03*
X59484Y1020000D03*
X58027Y1147650D03*
X75027Y1142650D03*
X66527Y1147650D03*
X66027Y1128650D03*
X57984Y1164000D03*
X100984Y81551D03*
X88484Y450500D03*
X83484Y672000D03*
Y680000D03*
Y688000D03*
Y696000D03*
Y704000D03*
Y709500D03*
Y715000D03*
X115984Y83500D03*
X124984Y66500D03*
X101984Y493500D03*
Y503500D03*
Y509500D03*
Y521500D03*
Y531500D03*
X115484Y659500D03*
Y663500D03*
X120984Y704000D03*
Y711000D03*
Y718000D03*
Y731000D03*
Y738000D03*
Y745000D03*
X145984Y249000D03*
Y257000D03*
X127484Y435000D03*
X134484Y656500D03*
X125484Y694500D03*
X133484D03*
X138484Y762000D03*
X147484Y980500D03*
X148484Y103342D03*
X148984Y126842D03*
X159466Y268728D03*
X169342Y283728D03*
X161984Y292000D03*
X155842Y282728D03*
X148484Y447228D03*
X148984Y470728D03*
X166984Y720000D03*
Y713000D03*
Y747000D03*
Y740000D03*
Y754000D03*
X148484Y810614D03*
X148984Y834114D03*
X159466Y998649D03*
X169342Y1010500D03*
X148984Y989000D03*
X155842Y1009500D03*
X167984Y1021500D03*
X148484Y1174000D03*
X148984Y1197500D03*
X183984Y663500D03*
Y659500D03*
Y652000D03*
X172984Y684500D03*
Y680500D03*
Y676500D03*
Y672500D03*
Y668500D03*
X178984Y706000D03*
X172984Y696500D03*
Y692500D03*
Y688500D03*
X190984Y706000D03*
X178984Y733000D03*
X187484D03*
G54D31*
X15500Y1227850D03*
X12941Y1234150D03*
X18059D03*
X188000Y1228850D03*
X185441Y1235150D03*
X190559D03*
G54D13*
X10000Y496500D03*
X17000D03*
X31500Y1220600D03*
X12000Y1221000D03*
X19000D03*
X27500Y1229400D03*
X35500D03*
X169000Y1229900D03*
X191500Y496000D03*
X184500D03*
X191500Y1221000D03*
X184500D03*
X173000Y1221100D03*
X177000Y1229900D03*
G54D22*
X12791Y267212D03*
Y993984D03*
X45500Y292484D03*
X55500Y389484D03*
X76500Y70484D03*
X75500Y127484D03*
X71000Y528984D03*
X68000Y576484D03*
X75000D03*
X65000Y1199984D03*
X100000Y122484D03*
X85500Y112484D03*
Y470484D03*
X87500Y486984D03*
X93000Y528984D03*
X87500D03*
X80000Y567984D03*
X91000Y631484D03*
X87000D03*
X98500D03*
X92500Y642984D03*
X84700D03*
X98500D03*
X88500Y813484D03*
X92500Y848984D03*
X85500Y833484D03*
X88500Y1176484D03*
X85500Y1196484D03*
X109500Y403484D03*
X113500Y481484D03*
X119000D03*
X124500D03*
Y490484D03*
X109000Y481484D03*
X105000Y631484D03*
X121000D03*
X114000D03*
X107000Y642984D03*
X121000D03*
X114000D03*
X111500Y768484D03*
X112500Y1131484D03*
X127000Y74484D03*
Y88484D03*
X136482Y267212D03*
X127500Y421484D03*
X135500Y481484D03*
X130000D03*
Y490484D03*
X135000Y631484D03*
X131000D03*
X138500Y642984D03*
X126500D03*
X127000Y783984D03*
Y796984D03*
X136482Y997133D03*
X127000Y1148484D03*
Y1162484D03*
X138500Y1183484D03*
X154500Y291484D03*
X148500Y390484D03*
G54D40*
X74626Y503776D03*
Y505350D03*
Y506925D03*
Y508500D03*
Y510075D03*
Y511650D03*
Y513224D03*
X90374D03*
Y511650D03*
Y510075D03*
Y508500D03*
Y506925D03*
Y505350D03*
Y503776D03*
X116126D03*
Y505350D03*
Y506925D03*
Y508500D03*
Y510075D03*
Y511650D03*
Y513224D03*
X131874D03*
Y511650D03*
Y510075D03*
Y508500D03*
Y506925D03*
Y505350D03*
Y503776D03*
G54D32*
X56243Y63842D03*
Y408878D03*
Y463878D03*
Y772264D03*
Y827264D03*
Y1136150D03*
Y1190650D03*
X64843Y63842D03*
X56743Y120342D03*
X65343D03*
X64843Y408878D03*
Y463878D03*
Y772264D03*
Y827264D03*
Y1136150D03*
Y1190650D03*
X146800Y64000D03*
X138200D03*
X147300Y119342D03*
X138700D03*
X147300Y407228D03*
X138700D03*
X147300Y463000D03*
X138700D03*
X146800Y773114D03*
X138200D03*
X147300Y826614D03*
X138700D03*
X147300Y1135000D03*
X138700D03*
X147300Y1190000D03*
X138700D03*
G54D41*
X56000Y1197327D03*
Y1200673D03*
X148500Y58173D03*
Y54827D03*
G54D14*
X9517Y734000D03*
Y748000D03*
Y741000D03*
X26517Y259500D03*
X13517Y502000D03*
Y511000D03*
Y515500D03*
Y506500D03*
Y520000D03*
X24017Y641000D03*
Y645500D03*
Y660000D03*
Y654000D03*
Y686000D03*
Y680500D03*
Y672500D03*
Y666500D03*
X20017Y734000D03*
X13517Y723000D03*
Y719000D03*
X20017Y748000D03*
Y741000D03*
X22017Y981500D03*
Y985500D03*
X55060Y75342D03*
X55017Y84192D03*
X32808Y268728D03*
X49517Y293000D03*
X43578Y282728D03*
X55017Y429228D03*
X55060Y420378D03*
X55017Y792614D03*
X55060Y783764D03*
X32808Y995500D03*
X44078Y1009500D03*
X55060Y1147650D03*
X55017Y1164000D03*
X63560Y75342D03*
X57078Y283728D03*
X72017Y410000D03*
X63060Y401378D03*
X63560Y420378D03*
X69017Y475000D03*
X60017Y641000D03*
Y660000D03*
Y655400D03*
Y647000D03*
Y685000D03*
Y679000D03*
Y672500D03*
Y666500D03*
X71017Y729000D03*
Y738500D03*
Y734500D03*
X63060Y764764D03*
X63560Y783764D03*
X74017Y834000D03*
X57578Y1010500D03*
X56517Y1020000D03*
X72060Y1142650D03*
X63560Y1147650D03*
X63060Y1128650D03*
X98017Y81551D03*
X85517Y450500D03*
X99017Y493500D03*
Y503500D03*
Y509500D03*
Y521500D03*
Y531500D03*
X80517Y672000D03*
Y680000D03*
Y688000D03*
Y696000D03*
Y704000D03*
Y709500D03*
Y715000D03*
X113017Y83500D03*
X122017Y66500D03*
X124517Y435000D03*
X112517Y659500D03*
Y663500D03*
X118017Y704000D03*
Y711000D03*
X122517Y694500D03*
X118017Y718000D03*
Y731000D03*
Y738000D03*
Y745000D03*
X145517Y103342D03*
X146017Y126842D03*
X143017Y249000D03*
Y257000D03*
X145517Y447228D03*
X146017Y470728D03*
X131517Y656500D03*
X130517Y694500D03*
X135517Y762000D03*
X145517Y810614D03*
X146017Y834114D03*
X144517Y980500D03*
X146017Y989000D03*
X145517Y1174000D03*
X146017Y1197500D03*
X156499Y268728D03*
X166375Y283728D03*
X159017Y292000D03*
X152875Y282728D03*
X170017Y684500D03*
Y680500D03*
Y676500D03*
Y672500D03*
Y668500D03*
Y696500D03*
Y692500D03*
Y688500D03*
X164017Y720000D03*
Y713000D03*
Y747000D03*
Y740000D03*
Y754000D03*
X156499Y998649D03*
X166375Y1010500D03*
X152875Y1009500D03*
X165017Y1021500D03*
X181017Y663500D03*
Y659500D03*
Y652000D03*
X176017Y706000D03*
X188017D03*
X176017Y733000D03*
X184517D03*
G54D23*
X12791Y264245D03*
Y991017D03*
X45500Y289517D03*
X55500Y386517D03*
X76500Y67517D03*
X75500Y124517D03*
X71000Y526017D03*
X68000Y573517D03*
X75000D03*
X65000Y1197017D03*
X85500Y109517D03*
X100000Y119517D03*
X85500Y467517D03*
X87500Y484017D03*
X93000Y526017D03*
X87500D03*
X80000Y565017D03*
X92500Y640017D03*
X84700D03*
X98500D03*
X91000Y628517D03*
X87000D03*
X98500D03*
X88500Y810517D03*
X92500Y846017D03*
X85500Y830517D03*
X88500Y1173517D03*
X85500Y1193517D03*
X109500Y400517D03*
X113500Y478517D03*
X119000D03*
X124500D03*
X109000D03*
X124500Y487517D03*
X107000Y640017D03*
X121000D03*
X114000D03*
X105000Y628517D03*
X121000D03*
X114000D03*
X111500Y765517D03*
X112500Y1128517D03*
X127000Y71517D03*
Y85517D03*
X136482Y264245D03*
X127500Y418517D03*
X135500Y478517D03*
X130000D03*
Y487517D03*
X135000Y628517D03*
X131000D03*
X138500Y640017D03*
X126500D03*
X127000Y781017D03*
Y794017D03*
X136482Y994166D03*
X127000Y1145517D03*
Y1159517D03*
X138500Y1180517D03*
X154500Y288517D03*
X148500Y387517D03*
G54D42*
X99260Y71441D03*
Y76559D03*
X97260Y101000D03*
X96260Y408441D03*
Y413559D03*
X99760Y460000D03*
X95760Y773441D03*
Y778559D03*
X97760Y822000D03*
Y1136941D03*
Y1142059D03*
Y1185000D03*
X106740Y74000D03*
X104740Y103559D03*
Y98441D03*
X103740Y411000D03*
X107240Y462559D03*
Y457441D03*
X103240Y776000D03*
X105240Y824559D03*
Y819441D03*
Y1139500D03*
Y1187559D03*
Y1182441D03*
G54D24*
X28579Y508429D03*
X30547D03*
Y524571D03*
X28579D03*
X38421Y508429D03*
Y524571D03*
X32516Y508429D03*
X34484D03*
X36453D03*
Y524571D03*
X34484D03*
X32516D03*
X170047Y509929D03*
X168079D03*
Y526071D03*
X170047D03*
X177921Y509929D03*
X175953D03*
X173984D03*
X172016D03*
Y526071D03*
X173984D03*
X175953D03*
X177921D03*
G54D33*
X55327Y97500D03*
Y113692D03*
X54827Y443728D03*
Y457228D03*
X55327Y778500D03*
X54827Y810000D03*
Y820614D03*
Y1173500D03*
Y1184000D03*
X71870Y56342D03*
X75216D03*
X71827Y75192D03*
X75173D03*
X58870Y70342D03*
X62216D03*
X58673Y97500D03*
X59370Y126842D03*
X62716D03*
X58673Y113692D03*
X71870Y401378D03*
X75216D03*
X58870Y415378D03*
X62216D03*
X71827Y420228D03*
X75173D03*
X58173Y443728D03*
Y457228D03*
X58870Y470378D03*
X62216D03*
X58673Y778500D03*
X71870Y764764D03*
X75216D03*
X71827Y783614D03*
X75173D03*
X58173Y810000D03*
Y820614D03*
X58870Y833764D03*
X62216D03*
X58870Y1142650D03*
X62216D03*
X71870Y1128650D03*
X75216D03*
X71827Y1147500D03*
X75173D03*
X58173Y1173500D03*
Y1184000D03*
X145327Y79842D03*
Y94000D03*
X131173Y107728D03*
X127827D03*
X144673Y112842D03*
X141327D03*
X133673Y124500D03*
X130327D03*
X144673Y400728D03*
X141327D03*
X145327Y428000D03*
Y413728D03*
X144673Y456728D03*
X141327D03*
X131173Y451614D03*
X127827D03*
X131673Y470728D03*
X128327D03*
X148173Y766500D03*
X144827D03*
X148173Y801500D03*
X144827D03*
X145327Y791500D03*
X144673Y820114D03*
X141327D03*
X131173Y815000D03*
X127827D03*
X132173Y834500D03*
X128827D03*
X145327Y1141500D03*
X144673Y1128500D03*
X141327D03*
X145327Y1151000D03*
Y1183500D03*
X131673Y1178500D03*
X128327D03*
X131173Y1198000D03*
X127827D03*
X148673Y79842D03*
Y94000D03*
Y428000D03*
Y413728D03*
Y791500D03*
Y1141500D03*
Y1151000D03*
Y1183500D03*
G54D15*
X34252Y64606D03*
Y56732D03*
Y48858D03*
X26378Y64606D03*
Y56732D03*
X34252Y88228D03*
Y80354D03*
Y72480D03*
X26378Y88228D03*
Y80354D03*
Y72480D03*
X34252Y103976D03*
Y96102D03*
X26378Y103976D03*
Y96102D03*
X34252Y412244D03*
Y435866D03*
Y427992D03*
Y420118D03*
X26378Y435866D03*
Y427992D03*
Y420118D03*
X34252Y451614D03*
Y443740D03*
X26378Y451614D03*
Y443740D03*
X34252Y467362D03*
Y459488D03*
X26378Y467362D03*
Y459488D03*
X34252Y775630D03*
Y799252D03*
Y791378D03*
Y783504D03*
X26378Y799252D03*
Y791378D03*
Y783504D03*
X34252Y822874D03*
Y815000D03*
Y807126D03*
X26378Y822874D03*
Y815000D03*
Y807126D03*
X34252Y830748D03*
X26378D03*
X34252Y1146890D03*
Y1139016D03*
X26378Y1146890D03*
X34252Y1170512D03*
Y1162638D03*
Y1154764D03*
X26378Y1170512D03*
Y1162638D03*
Y1154764D03*
X34252Y1194134D03*
Y1186260D03*
Y1178386D03*
X26378Y1194134D03*
Y1186260D03*
Y1178386D03*
X169291Y48858D03*
Y56732D03*
Y64606D03*
Y72480D03*
Y80354D03*
Y88228D03*
Y96102D03*
Y103976D03*
Y412244D03*
Y420118D03*
Y427992D03*
Y435866D03*
Y443740D03*
Y451614D03*
Y459488D03*
Y467362D03*
Y775630D03*
Y783504D03*
Y791378D03*
Y799252D03*
Y807126D03*
Y815000D03*
Y822874D03*
Y830748D03*
Y1139016D03*
Y1146890D03*
Y1154764D03*
Y1162638D03*
Y1170512D03*
Y1178386D03*
Y1186260D03*
Y1194134D03*
X177165Y48858D03*
Y56732D03*
Y64606D03*
Y72480D03*
Y80354D03*
Y88228D03*
Y96102D03*
Y412244D03*
Y420118D03*
Y427992D03*
Y435866D03*
Y443740D03*
Y451614D03*
Y459488D03*
Y775630D03*
Y783504D03*
Y791378D03*
Y799252D03*
Y807126D03*
Y815000D03*
Y822874D03*
Y1139016D03*
Y1146890D03*
Y1154764D03*
Y1162638D03*
Y1170512D03*
Y1178386D03*
Y1186260D03*
G54D25*
X25429Y511579D03*
Y513547D03*
Y515516D03*
Y517484D03*
Y519453D03*
Y521421D03*
X41571D03*
Y519453D03*
Y517484D03*
Y515516D03*
Y513547D03*
Y511579D03*
X164929Y513079D03*
Y522921D03*
Y520953D03*
Y518984D03*
Y517016D03*
Y515047D03*
X181071Y513079D03*
Y515047D03*
Y517016D03*
Y518984D03*
Y520953D03*
Y522921D03*
G54D34*
X50150Y385441D03*
X43850Y388000D03*
X50150Y390559D03*
X71650Y86441D03*
X65350Y106000D03*
X71650Y108559D03*
Y103441D03*
X65350Y89000D03*
X71650Y91559D03*
Y432441D03*
X65350Y451500D03*
X71650Y454059D03*
Y448941D03*
X65350Y435000D03*
X71650Y437559D03*
X65350Y799500D03*
X71650Y802059D03*
Y796941D03*
X65350Y815500D03*
X71650Y818059D03*
Y812941D03*
X71150Y1173441D03*
X64850Y1160000D03*
X71150Y1162559D03*
Y1157441D03*
X64850Y1176000D03*
X71150Y1178559D03*
X88350Y123500D03*
X94650Y126059D03*
Y120941D03*
X80850Y848500D03*
X87150Y845941D03*
Y851059D03*
X114650Y131500D03*
X108350Y128941D03*
Y134059D03*
X138650Y73000D03*
X132350Y70441D03*
Y75559D03*
Y86441D03*
X138650Y89000D03*
X132350Y91559D03*
X139150Y416500D03*
X132850Y413941D03*
Y419059D03*
X139150Y432500D03*
X132850Y429941D03*
Y435059D03*
X133350Y780141D03*
X139650Y782700D03*
X133350Y785259D03*
X138650Y798500D03*
X132350Y795941D03*
Y801059D03*
X138650Y1146000D03*
X132350Y1143441D03*
Y1148559D03*
X138650Y1162000D03*
X132350Y1159441D03*
Y1164559D03*
X153850Y386441D03*
X160150Y389000D03*
X153850Y391559D03*
X166850Y853441D03*
Y858559D03*
X173150Y856000D03*
G54D43*
X85941Y104740D03*
X91059D03*
Y97260D03*
X88500D03*
X85941D03*
X91059Y455260D03*
X88500D03*
X85941D03*
Y462740D03*
X91059D03*
X85941Y825740D03*
X91059D03*
Y818260D03*
X88500D03*
X85941D03*
Y1188740D03*
X91059D03*
Y1181260D03*
X88500D03*
X85941D03*
X118559Y71260D03*
X113441D03*
Y78740D03*
X116000D03*
X118559D03*
X117559Y408260D03*
X112441D03*
Y415740D03*
X115000D03*
X117559D03*
X117059Y773260D03*
X111941D03*
Y780740D03*
X114500D03*
X117059D03*
X118059Y1136260D03*
X112941D03*
Y1143740D03*
X115500D03*
X118059D03*
G54D16*
X26378Y48858D03*
Y412244D03*
Y775630D03*
Y1139016D03*
X177165Y103976D03*
Y467362D03*
Y830748D03*
Y1194134D03*
G54D26*
X33500Y516500D03*
X173000Y518000D03*
G54D35*
X37000Y384600D03*
Y390400D03*
X72000Y463100D03*
Y468900D03*
X82300Y121100D03*
Y126900D03*
X122500Y105100D03*
Y110900D03*
X185000Y868100D03*
Y873900D03*
G54D17*
X14700Y144531D03*
Y137531D03*
X23400Y383500D03*
X14600Y379500D03*
Y387500D03*
X18600Y867000D03*
Y860000D03*
X55600Y850500D03*
X71600Y137500D03*
X64400Y846500D03*
Y854500D03*
X80400Y133500D03*
Y141500D03*
X122100Y131000D03*
Y139000D03*
X130900Y135000D03*
X189054Y145631D03*
Y138631D03*
X194900Y388000D03*
X186100Y384000D03*
Y392000D03*
X192000Y867500D03*
X194400Y856000D03*
X185600Y852000D03*
Y860000D03*
X192000Y874500D03*
G54D44*
X95500Y388000D03*
X158000Y17500D03*
X166960Y1304230D03*
G54D27*
X27000Y531016D03*
X19000D03*
X23000D03*
X17000Y989516D03*
X33000Y531016D03*
X64543Y54858D03*
X77000Y87016D03*
Y104516D03*
X66561Y279244D03*
X77000Y432516D03*
Y450016D03*
X76500Y526016D03*
X71000Y534016D03*
X76500D03*
X68000Y565016D03*
X75000D03*
X78500Y608516D03*
X72000Y628516D03*
X68000D03*
X77000Y800516D03*
Y813516D03*
X67061Y1006016D03*
X76500Y1157516D03*
Y1173516D03*
X96000Y53216D03*
X91500D03*
Y109516D03*
Y467516D03*
X82000Y526016D03*
X93000Y534016D03*
X87500D03*
X82000D03*
X101000Y556016D03*
X91000D03*
X95500D03*
X80000D03*
X93000Y565016D03*
X101000D03*
X85000D03*
X80800Y640016D03*
X80900Y628516D03*
X91500Y830516D03*
Y1193516D03*
X106500Y53216D03*
X102500D03*
X103000Y130016D03*
X113500Y400516D03*
X115000Y420516D03*
X106500Y500516D03*
X113500Y487516D03*
X119000D03*
X116000Y524016D03*
X106000Y531516D03*
X110000D03*
X114500Y556016D03*
X124500Y555016D03*
X107500Y556016D03*
X124500Y565016D03*
X107500D03*
X117000D03*
X117500Y765516D03*
X114500Y785516D03*
X115500Y1148516D03*
X118500Y1128516D03*
X143500Y55016D03*
X135500Y487516D03*
X131500Y555016D03*
X135500D03*
Y565016D03*
X131500D03*
X129000Y1129016D03*
X166500Y532016D03*
Y539016D03*
X161000Y854516D03*
X175858Y279244D03*
X171500Y532016D03*
Y539016D03*
X176500Y532016D03*
X175858Y1006016D03*
G54D45*
X101339Y587000D03*
X98780D03*
X96220D03*
X93661D03*
X91102D03*
X88543D03*
X85984D03*
X83425D03*
Y610000D03*
X85984D03*
X88543D03*
X91102D03*
X93661D03*
X96220D03*
X98780D03*
X101339D03*
X111575Y587000D03*
X109016D03*
X106457D03*
X103898D03*
Y610000D03*
X106457D03*
X109016D03*
X111575D03*
G54D36*
X35260Y643441D03*
Y646000D03*
Y648559D03*
X42740D03*
Y646000D03*
Y643441D03*
X35260Y654441D03*
Y657000D03*
Y659559D03*
X42740D03*
Y657000D03*
Y654441D03*
X35260Y666941D03*
Y669500D03*
Y672059D03*
X42740D03*
Y669500D03*
Y666941D03*
X35260Y679441D03*
Y682000D03*
Y684559D03*
X42740D03*
Y682000D03*
Y679441D03*
G54D18*
X22780Y155131D03*
X27480Y880000D03*
X57820Y155131D03*
X46023Y358300D03*
X62520Y880000D03*
X46023Y1085072D03*
X81063Y358300D03*
Y1085072D03*
X121380Y358100D03*
X119980Y1085072D03*
X145634Y155131D03*
X141880Y883400D03*
X155020Y1085072D03*
X156420Y358100D03*
X176920Y883400D03*
X180674Y155131D03*
G54D19*
X26516Y255500D03*
X19307Y262728D03*
X22516Y251500D03*
X15016Y641000D03*
Y660000D03*
Y654000D03*
Y645500D03*
Y686000D03*
Y680500D03*
Y672500D03*
Y666500D03*
X13516Y715000D03*
Y727000D03*
X20016Y974500D03*
X14016Y1239500D03*
X54559Y56342D03*
X55016Y79692D03*
X32807Y263728D03*
X43577Y277728D03*
X49516Y289000D03*
X54559Y401378D03*
X55016Y424728D03*
X51016Y641000D03*
Y660000D03*
Y654000D03*
Y647000D03*
Y685000D03*
Y679000D03*
Y672500D03*
Y666500D03*
X34516Y727500D03*
X54559Y764764D03*
X55016Y788114D03*
X44077Y1004500D03*
X32807Y990500D03*
X54559Y1128650D03*
X55016Y1152000D03*
X69016Y641000D03*
Y657500D03*
Y651500D03*
Y647000D03*
Y685000D03*
Y679000D03*
Y672500D03*
Y666500D03*
X71016Y704000D03*
Y709500D03*
Y719000D03*
Y724000D03*
Y715000D03*
Y742500D03*
Y751500D03*
X63516Y778500D03*
X56516Y1024000D03*
Y1016000D03*
X88516Y92000D03*
X99016Y478500D03*
Y483425D03*
Y498500D03*
Y488500D03*
Y517500D03*
X80516Y676000D03*
Y684000D03*
Y692000D03*
Y700000D03*
X99016Y706500D03*
Y711000D03*
X95516Y731000D03*
Y738000D03*
Y745000D03*
X104600Y81551D03*
X112516Y667500D03*
Y671500D03*
Y675500D03*
Y679500D03*
Y683500D03*
Y687500D03*
X106516Y706500D03*
Y711000D03*
X112516Y693000D03*
X106516Y731000D03*
Y718000D03*
Y738000D03*
Y745000D03*
X118016Y752000D03*
X145516Y107842D03*
Y98842D03*
X137016Y107842D03*
X138516Y126842D03*
X128016Y118000D03*
X143016Y253000D03*
X142998Y262728D03*
X129516Y408000D03*
X145516Y442728D03*
Y451728D03*
X128516Y456728D03*
X137016Y451728D03*
X137516Y470728D03*
X129516Y728500D03*
X145516Y806114D03*
Y815114D03*
X128516Y820114D03*
X137016Y815114D03*
X137516Y834114D03*
X146016Y985000D03*
X142998Y992649D03*
X145516Y1160500D03*
Y1178500D03*
X128516Y1183500D03*
X137516Y1197500D03*
X156498Y263728D03*
X152874Y277728D03*
X159016Y288000D03*
X170016Y663500D03*
Y659500D03*
Y651500D03*
X164016Y706000D03*
Y733000D03*
X149016Y729000D03*
X152874Y1004500D03*
X156498Y993649D03*
X165016Y1025500D03*
Y1017500D03*
X188516Y515500D03*
Y521000D03*
Y532000D03*
Y526500D03*
X176016Y720000D03*
Y713000D03*
Y747000D03*
Y740000D03*
X186516Y1240500D03*
G54D28*
X27000Y533983D03*
X19000D03*
X23000D03*
X17000Y992483D03*
X33000Y533983D03*
X64543Y57825D03*
X77000Y107483D03*
Y89983D03*
X66561Y282211D03*
X77000Y452983D03*
Y435483D03*
X71000Y536983D03*
X76500D03*
Y528983D03*
X68000Y567983D03*
X75000D03*
X78500Y611483D03*
X72000Y631483D03*
X68000D03*
X77000Y803483D03*
Y816483D03*
X67061Y1008983D03*
X76500Y1160483D03*
Y1176483D03*
X96000Y56183D03*
X91500D03*
Y112483D03*
Y470483D03*
X93000Y536983D03*
X87500D03*
X82000D03*
Y528983D03*
X101000Y558983D03*
X91000D03*
X95500D03*
X80000D03*
X93000Y567983D03*
X101000D03*
X85000D03*
X80900Y631483D03*
X80800Y642983D03*
X91500Y833483D03*
Y1196483D03*
X106500Y56183D03*
X102500D03*
X103000Y132983D03*
X113500Y403483D03*
X115000Y423483D03*
X113500Y490483D03*
X119000D03*
X106500Y503483D03*
X106000Y534483D03*
X110000D03*
X116000Y526983D03*
X114500Y558983D03*
X124500Y557983D03*
X107500Y558983D03*
X124500Y567983D03*
X107500D03*
X117000D03*
X117500Y768483D03*
X114500Y788483D03*
X118500Y1131483D03*
X115500Y1151483D03*
X143500Y57983D03*
X135500Y490483D03*
X131500Y557983D03*
X135500D03*
Y567983D03*
X131500D03*
X129000Y1131983D03*
X166500Y534983D03*
Y541983D03*
X161000Y857483D03*
X175858Y282211D03*
X171500Y534983D03*
Y541983D03*
X176500Y534983D03*
X175858Y1008983D03*
G54D37*
X77900Y63000D03*
X72100D03*
X76743Y119500D03*
X70943D03*
X78400Y415000D03*
X72600D03*
X77400Y778000D03*
X71600D03*
X76900Y828500D03*
X71100D03*
X76400Y1134000D03*
X70600D03*
X76400Y1191000D03*
X70600D03*
X79600Y858500D03*
X85400D03*
X110400Y121000D03*
X104600D03*
X125100Y461000D03*
Y1192500D03*
X126600Y59500D03*
X132400D03*
X126875Y399500D03*
X132675D03*
X130900Y461000D03*
X132100Y766500D03*
X137900D03*
X126100Y829114D03*
X131900D03*
X126600Y1137500D03*
X132400D03*
X130900Y1192500D03*
X166600Y389000D03*
X172400D03*
G54D46*
X101772Y1287047D03*
G54D47*
G01X-320500Y-470483D02*
Y2626000D01*
X2967000D01*
Y-470483D01*
X-320500D01*
G01X329322Y-314459D02*
Y-319459D01*
G01X327865Y-314459D02*
X330779D01*
G01X335689Y-319459D02*
X333155D01*
Y-314459D01*
X335689D01*
G01X334675Y-316876D02*
X333155D01*
G01X338255Y-314459D02*
Y-319459D01*
X340789D01*
G01X344622Y-319626D02*
X344495Y-319542D01*
Y-319376D01*
X344622Y-319292D01*
X344749Y-319376D01*
Y-319542D01*
X344622Y-319626D01*
G01Y-317376D02*
X344495Y-317292D01*
Y-317126D01*
X344622Y-317042D01*
X344749Y-317126D01*
Y-317292D01*
X344622Y-317376D01*
G01X349405Y-321126D02*
X348772Y-320292D01*
X348455Y-319459D01*
Y-316126D01*
X348772Y-315292D01*
X349405Y-314459D01*
G01X354822D02*
X354315Y-314626D01*
X353935Y-315042D01*
X353682Y-315542D01*
X353492Y-316209D01*
X353429Y-316959D01*
X353492Y-317709D01*
X353682Y-318376D01*
X353935Y-318876D01*
X354315Y-319292D01*
X354822Y-319459D01*
X355329Y-319292D01*
X355709Y-318876D01*
X355962Y-318376D01*
X356152Y-317709D01*
X356215Y-316959D01*
X356152Y-316209D01*
X355962Y-315542D01*
X355709Y-315042D01*
X355329Y-314626D01*
X354822Y-314459D01*
G01X358529Y-318459D02*
X358909Y-319042D01*
X359415Y-319376D01*
X359985Y-319459D01*
X360492Y-319376D01*
X360999Y-318959D01*
X361315Y-318459D01*
X361379Y-317959D01*
X361252Y-317376D01*
X360809Y-316959D01*
X360365Y-316792D01*
X359795D01*
G01X360365D02*
X360745Y-316542D01*
X361062Y-316126D01*
X361189Y-315626D01*
X361062Y-315126D01*
X360745Y-314709D01*
X360175Y-314459D01*
X359605Y-314542D01*
X359035Y-314876D01*
G01X365339Y-321126D02*
X365972Y-320292D01*
X366289Y-319459D01*
Y-316126D01*
X365972Y-315292D01*
X365339Y-314459D01*
G01X368729Y-318459D02*
X369109Y-319042D01*
X369615Y-319376D01*
X370185Y-319459D01*
X370692Y-319376D01*
X371199Y-318959D01*
X371515Y-318459D01*
X371579Y-317959D01*
X371452Y-317376D01*
X371009Y-316959D01*
X370565Y-316792D01*
X369995D01*
G01X370565D02*
X370945Y-316542D01*
X371262Y-316126D01*
X371389Y-315626D01*
X371262Y-315126D01*
X370945Y-314709D01*
X370375Y-314459D01*
X369805Y-314542D01*
X369235Y-314876D01*
G01X374019Y-315292D02*
X374399Y-314792D01*
X374842Y-314542D01*
X375349Y-314459D01*
X375982Y-314626D01*
X376425Y-315042D01*
X376552Y-315542D01*
X376489Y-316042D01*
X376235Y-316459D01*
X374969Y-317292D01*
X374399Y-317876D01*
X374019Y-318709D01*
X373892Y-319459D01*
X376552D01*
G01X380195D02*
X380322Y-318376D01*
X380512Y-317459D01*
X380765Y-316626D01*
X381082Y-315709D01*
X381589Y-314459D01*
X379055D01*
G01X384599Y-317792D02*
X386245D01*
G01X389319Y-315292D02*
X389699Y-314792D01*
X390142Y-314542D01*
X390649Y-314459D01*
X391282Y-314626D01*
X391725Y-315042D01*
X391852Y-315542D01*
X391789Y-316042D01*
X391535Y-316459D01*
X390269Y-317292D01*
X389699Y-317876D01*
X389319Y-318709D01*
X389192Y-319459D01*
X391852D01*
G01X394229Y-318459D02*
X394609Y-319042D01*
X395115Y-319376D01*
X395685Y-319459D01*
X396192Y-319376D01*
X396699Y-318959D01*
X397015Y-318459D01*
X397079Y-317959D01*
X396952Y-317376D01*
X396509Y-316959D01*
X396065Y-316792D01*
X395495D01*
G01X396065D02*
X396445Y-316542D01*
X396762Y-316126D01*
X396889Y-315626D01*
X396762Y-315126D01*
X396445Y-314709D01*
X395875Y-314459D01*
X395305Y-314542D01*
X394735Y-314876D01*
G01X401482Y-319459D02*
Y-314459D01*
X399139Y-318042D01*
X402305D01*
G01X404429Y-318709D02*
X404809Y-319126D01*
X405252Y-319376D01*
X405822Y-319459D01*
X406392Y-319292D01*
X406835Y-318959D01*
X407152Y-318376D01*
X407215Y-317709D01*
X407089Y-317042D01*
X406772Y-316626D01*
X406329Y-316292D01*
X405885Y-316209D01*
X405442Y-316292D01*
X404872Y-316626D01*
X405062Y-314459D01*
X406772D01*
G01X414819Y-319459D02*
Y-314459D01*
X417225D01*
G01X416339Y-316876D02*
X414819D01*
G01X419539Y-319459D02*
X421122Y-314459D01*
X422705Y-319459D01*
G01X422135Y-317709D02*
X420109D01*
G01X424892Y-319459D02*
X427552Y-314459D01*
G01X424892D02*
X427552Y-319459D01*
G01X431322Y-319626D02*
X431195Y-319542D01*
Y-319376D01*
X431322Y-319292D01*
X431449Y-319376D01*
Y-319542D01*
X431322Y-319626D01*
G01Y-317376D02*
X431195Y-317292D01*
Y-317126D01*
X431322Y-317042D01*
X431449Y-317126D01*
Y-317292D01*
X431322Y-317376D01*
G01X436105Y-321126D02*
X435472Y-320292D01*
X435155Y-319459D01*
Y-316126D01*
X435472Y-315292D01*
X436105Y-314459D01*
G01X441522D02*
X441015Y-314626D01*
X440635Y-315042D01*
X440382Y-315542D01*
X440192Y-316209D01*
X440129Y-316959D01*
X440192Y-317709D01*
X440382Y-318376D01*
X440635Y-318876D01*
X441015Y-319292D01*
X441522Y-319459D01*
X442029Y-319292D01*
X442409Y-318876D01*
X442662Y-318376D01*
X442852Y-317709D01*
X442915Y-316959D01*
X442852Y-316209D01*
X442662Y-315542D01*
X442409Y-315042D01*
X442029Y-314626D01*
X441522Y-314459D01*
G01X445229Y-318459D02*
X445609Y-319042D01*
X446115Y-319376D01*
X446685Y-319459D01*
X447192Y-319376D01*
X447699Y-318959D01*
X448015Y-318459D01*
X448079Y-317959D01*
X447952Y-317376D01*
X447509Y-316959D01*
X447065Y-316792D01*
X446495D01*
G01X447065D02*
X447445Y-316542D01*
X447762Y-316126D01*
X447889Y-315626D01*
X447762Y-315126D01*
X447445Y-314709D01*
X446875Y-314459D01*
X446305Y-314542D01*
X445735Y-314876D01*
G01X452039Y-321126D02*
X452672Y-320292D01*
X452989Y-319459D01*
Y-316126D01*
X452672Y-315292D01*
X452039Y-314459D01*
G01X455429Y-318459D02*
X455809Y-319042D01*
X456315Y-319376D01*
X456885Y-319459D01*
X457392Y-319376D01*
X457899Y-318959D01*
X458215Y-318459D01*
X458279Y-317959D01*
X458152Y-317376D01*
X457709Y-316959D01*
X457265Y-316792D01*
X456695D01*
G01X457265D02*
X457645Y-316542D01*
X457962Y-316126D01*
X458089Y-315626D01*
X457962Y-315126D01*
X457645Y-314709D01*
X457075Y-314459D01*
X456505Y-314542D01*
X455935Y-314876D01*
G01X460845Y-318876D02*
X461289Y-319292D01*
X461795Y-319459D01*
X462302Y-319292D01*
X462745Y-318792D01*
X463062Y-318042D01*
X463189Y-317292D01*
Y-316376D01*
X463062Y-315626D01*
X462745Y-314959D01*
X462365Y-314626D01*
X461922Y-314459D01*
X461415Y-314626D01*
X461035Y-314959D01*
X460782Y-315459D01*
X460655Y-316126D01*
X460782Y-316709D01*
X461099Y-317292D01*
X461479Y-317626D01*
X461922Y-317709D01*
X462429Y-317542D01*
X462809Y-317126D01*
X463189Y-316376D01*
G01X466895Y-319459D02*
X467022Y-318376D01*
X467212Y-317459D01*
X467465Y-316626D01*
X467782Y-315709D01*
X468289Y-314459D01*
X465755D01*
G01X471299Y-317792D02*
X472945D01*
G01X475829Y-318459D02*
X476209Y-319042D01*
X476715Y-319376D01*
X477285Y-319459D01*
X477792Y-319376D01*
X478299Y-318959D01*
X478615Y-318459D01*
X478679Y-317959D01*
X478552Y-317376D01*
X478109Y-316959D01*
X477665Y-316792D01*
X477095D01*
G01X477665D02*
X478045Y-316542D01*
X478362Y-316126D01*
X478489Y-315626D01*
X478362Y-315126D01*
X478045Y-314709D01*
X477475Y-314459D01*
X476905Y-314542D01*
X476335Y-314876D01*
G01X481119Y-317376D02*
X481562Y-316792D01*
X481942Y-316459D01*
X482449Y-316292D01*
X482892Y-316459D01*
X483209Y-316792D01*
X483462Y-317292D01*
X483525Y-317876D01*
X483462Y-318376D01*
X483209Y-318876D01*
X482829Y-319292D01*
X482385Y-319459D01*
X481879Y-319292D01*
X481435Y-318792D01*
X481182Y-318042D01*
X481119Y-317209D01*
X481245Y-316126D01*
X481435Y-315542D01*
X481752Y-314959D01*
X482195Y-314542D01*
X482639Y-314459D01*
X483082Y-314626D01*
X483399Y-315042D01*
G01X487422Y-319459D02*
Y-314459D01*
X486662Y-315459D01*
G01Y-319459D02*
X488182D01*
G01X493282D02*
Y-314459D01*
X490939Y-318042D01*
X494105D01*
G01X317322Y-249459D02*
Y-324459D01*
X817322D01*
Y-249459D01*
X317322D01*
G01X512322D02*
Y-324459D01*
G01Y-299459D02*
X615322D01*
Y-274459D01*
G01X512322D02*
X615322D01*
G01X622829Y-309459D02*
Y-304459D01*
X624095D01*
X624602Y-304709D01*
X624982Y-305042D01*
X625299Y-305542D01*
X625552Y-306126D01*
X625615Y-306959D01*
X625552Y-307792D01*
X625299Y-308376D01*
X624982Y-308876D01*
X624602Y-309209D01*
X624095Y-309459D01*
X622829D01*
G01X627739D02*
X629322Y-304459D01*
X630905Y-309459D01*
G01X630335Y-307709D02*
X628309D01*
G01X634422Y-304459D02*
Y-309459D01*
G01X632965Y-304459D02*
X635879D01*
G01X640789Y-309459D02*
X638255D01*
Y-304459D01*
X640789D01*
G01X639775Y-306876D02*
X638255D01*
G01X644622Y-309626D02*
X644495Y-309542D01*
Y-309376D01*
X644622Y-309292D01*
X644749Y-309376D01*
Y-309542D01*
X644622Y-309626D01*
G01Y-307376D02*
X644495Y-307292D01*
Y-307126D01*
X644622Y-307042D01*
X644749Y-307126D01*
Y-307292D01*
X644622Y-307376D01*
G01X617322Y-249459D02*
Y-324459D01*
G01X615322Y-249459D02*
Y-324459D01*
G01X622955Y-284459D02*
Y-279459D01*
X624475D01*
X624982Y-279709D01*
X625362Y-280292D01*
X625489Y-280959D01*
X625362Y-281626D01*
X625045Y-282126D01*
X624475Y-282376D01*
X622955D01*
G01X628182Y-284626D02*
X630462Y-279459D01*
G01X632965Y-284459D02*
Y-279459D01*
X635879Y-284459D01*
Y-279459D01*
G01X639522Y-284626D02*
X639395Y-284542D01*
Y-284376D01*
X639522Y-284292D01*
X639649Y-284376D01*
Y-284542D01*
X639522Y-284626D01*
G01Y-282376D02*
X639395Y-282292D01*
Y-282126D01*
X639522Y-282042D01*
X639649Y-282126D01*
Y-282292D01*
X639522Y-282376D01*
G01X617322Y-299459D02*
X817322D01*
G01X622955Y-259459D02*
Y-254459D01*
X624475D01*
X624982Y-254709D01*
X625362Y-255292D01*
X625489Y-255959D01*
X625362Y-256626D01*
X625045Y-257126D01*
X624475Y-257376D01*
X622955D01*
G01X628055Y-259459D02*
Y-254459D01*
X629639D01*
X630145Y-254709D01*
X630462Y-255042D01*
X630589Y-255709D01*
X630462Y-256376D01*
X630082Y-256792D01*
X629639Y-257042D01*
X628055D01*
G01X629639D02*
X630589Y-259459D01*
G01X634422D02*
X633915Y-259376D01*
X633472Y-259042D01*
X633092Y-258542D01*
X632839Y-257959D01*
X632712Y-257292D01*
Y-256626D01*
X632839Y-255959D01*
X633092Y-255376D01*
X633472Y-254876D01*
X633915Y-254542D01*
X634422Y-254459D01*
X634929Y-254542D01*
X635372Y-254876D01*
X635752Y-255376D01*
X636005Y-255959D01*
X636132Y-256626D01*
Y-257292D01*
X636005Y-257959D01*
X635752Y-258542D01*
X635372Y-259042D01*
X634929Y-259376D01*
X634422Y-259459D01*
G01X638255Y-258459D02*
X638572Y-258959D01*
X638952Y-259292D01*
X639395Y-259459D01*
X639902Y-259292D01*
X640282Y-258959D01*
X640662Y-258459D01*
X640789Y-257792D01*
Y-254459D01*
G01X645889Y-259459D02*
X643355D01*
Y-254459D01*
X645889D01*
G01X644875Y-256876D02*
X643355D01*
G01X651115Y-254876D02*
X650735Y-254626D01*
X650292Y-254459D01*
X649785D01*
X649215Y-254709D01*
X648772Y-255126D01*
X648455Y-255626D01*
X648202Y-256459D01*
X648139Y-257209D01*
X648265Y-257959D01*
X648455Y-258459D01*
X648835Y-258959D01*
X649279Y-259292D01*
X649722Y-259459D01*
X650165D01*
X650609Y-259292D01*
X650989Y-259042D01*
X651305Y-258709D01*
G01X654822Y-254459D02*
Y-259459D01*
G01X653365Y-254459D02*
X656279D01*
G01X659922Y-259626D02*
X659795Y-259542D01*
Y-259376D01*
X659922Y-259292D01*
X660049Y-259376D01*
Y-259542D01*
X659922Y-259626D01*
G01Y-257376D02*
X659795Y-257292D01*
Y-257126D01*
X659922Y-257042D01*
X660049Y-257126D01*
Y-257292D01*
X659922Y-257376D01*
G01X617322Y-274459D02*
X817322D01*
G01X734955Y-301959D02*
Y-306959D01*
X737489D01*
G01X740562Y-301959D02*
X742082D01*
G01X741322D02*
Y-306959D01*
G01X740562D02*
X742082D01*
G01X746929Y-304292D02*
X747182Y-304042D01*
X747372Y-303626D01*
X747499Y-303042D01*
X747372Y-302542D01*
X747119Y-302209D01*
X746675Y-301959D01*
X744965D01*
Y-306959D01*
X747055D01*
X747499Y-306626D01*
X747752Y-306126D01*
X747879Y-305542D01*
X747752Y-304959D01*
X747372Y-304459D01*
X746929Y-304292D01*
X744965D01*
G01X751522Y-307126D02*
X751395Y-307042D01*
Y-306876D01*
X751522Y-306792D01*
X751649Y-306876D01*
Y-307042D01*
X751522Y-307126D01*
G01Y-304876D02*
X751395Y-304792D01*
Y-304626D01*
X751522Y-304542D01*
X751649Y-304626D01*
Y-304792D01*
X751522Y-304876D01*
G01X732322Y-299459D02*
Y-324459D01*
G01X779222Y-301959D02*
Y-306959D01*
G01X777765Y-301959D02*
X780679D01*
G01X784322Y-306959D02*
X783942Y-306876D01*
X783562Y-306542D01*
X783309Y-305959D01*
X783182Y-305292D01*
X783309Y-304626D01*
X783562Y-304042D01*
X783942Y-303709D01*
X784322Y-303626D01*
X784702Y-303709D01*
X785082Y-304042D01*
X785335Y-304626D01*
X785399Y-305292D01*
X785335Y-305959D01*
X785082Y-306542D01*
X784702Y-306876D01*
X784322Y-306959D01*
G01X789422D02*
X789042Y-306876D01*
X788662Y-306542D01*
X788409Y-305959D01*
X788282Y-305292D01*
X788409Y-304626D01*
X788662Y-304042D01*
X789042Y-303709D01*
X789422Y-303626D01*
X789802Y-303709D01*
X790182Y-304042D01*
X790435Y-304626D01*
X790499Y-305292D01*
X790435Y-305959D01*
X790182Y-306542D01*
X789802Y-306876D01*
X789422Y-306959D01*
G01X794522D02*
Y-301959D01*
G01X799622Y-307126D02*
X799495Y-307042D01*
Y-306876D01*
X799622Y-306792D01*
X799749Y-306876D01*
Y-307042D01*
X799622Y-307126D01*
G01Y-304876D02*
X799495Y-304792D01*
Y-304626D01*
X799622Y-304542D01*
X799749Y-304626D01*
Y-304792D01*
X799622Y-304876D01*
G01X775322Y-299459D02*
Y-324459D01*
G01Y-274459D02*
Y-299459D01*
G01X777955Y-281959D02*
Y-276959D01*
X779539D01*
X780045Y-277209D01*
X780362Y-277542D01*
X780489Y-278209D01*
X780362Y-278876D01*
X779982Y-279292D01*
X779539Y-279542D01*
X777955D01*
G01X779539D02*
X780489Y-281959D01*
G01X785589D02*
X783055D01*
Y-276959D01*
X785589D01*
G01X784575Y-279376D02*
X783055D01*
G01X787839Y-276959D02*
X789422Y-281959D01*
X791005Y-276959D01*
G01X794522Y-282126D02*
X794395Y-282042D01*
Y-281876D01*
X794522Y-281792D01*
X794649Y-281876D01*
Y-282042D01*
X794522Y-282126D01*
G01Y-279876D02*
X794395Y-279792D01*
Y-279626D01*
X794522Y-279542D01*
X794649Y-279626D01*
Y-279792D01*
X794522Y-279876D01*
G01X798082Y-326159D02*
X798162Y-326084D01*
X798222Y-325959D01*
X798262Y-325784D01*
X798222Y-325634D01*
X798142Y-325534D01*
X798002Y-325459D01*
X797462D01*
Y-326959D01*
X798122D01*
X798262Y-326859D01*
X798342Y-326709D01*
X798382Y-326534D01*
X798342Y-326359D01*
X798222Y-326209D01*
X798082Y-326159D01*
X797462D01*
G01X799482Y-326959D02*
Y-325959D01*
G01Y-326134D02*
X799402Y-326034D01*
X799282Y-325984D01*
X799142Y-325959D01*
X799002Y-326009D01*
X798882Y-326109D01*
X798802Y-326259D01*
X798762Y-326459D01*
X798802Y-326659D01*
X798882Y-326809D01*
X799002Y-326909D01*
X799142Y-326959D01*
X799282Y-326934D01*
X799402Y-326859D01*
X799482Y-326759D01*
G01X800022Y-326784D02*
X800122Y-326884D01*
X800262Y-326959D01*
X800382D01*
X800502Y-326909D01*
X800582Y-326834D01*
X800622Y-326734D01*
X800602Y-326584D01*
X800522Y-326509D01*
X800162Y-326359D01*
X800082Y-326184D01*
X800122Y-326059D01*
X800202Y-325984D01*
X800322Y-325959D01*
X800442Y-325984D01*
X800562Y-326059D01*
G01X801222Y-326284D02*
X801862D01*
X801802Y-326109D01*
X801702Y-326009D01*
X801562Y-325959D01*
X801422Y-325984D01*
X801302Y-326059D01*
X801222Y-326234D01*
X801182Y-326384D01*
Y-326534D01*
X801222Y-326684D01*
X801322Y-326834D01*
X801442Y-326934D01*
X801582Y-326959D01*
X801722Y-326909D01*
X801862Y-326759D01*
G01X802362Y-326959D02*
Y-325459D01*
G01Y-326209D02*
X802462Y-326059D01*
X802582Y-325984D01*
X802702Y-325959D01*
X802882Y-326009D01*
X803002Y-326109D01*
X803082Y-326284D01*
Y-326484D01*
X803042Y-326684D01*
X802962Y-326834D01*
X802822Y-326934D01*
X802702Y-326959D01*
X802582Y-326934D01*
X802462Y-326859D01*
X802362Y-326734D01*
G01X803922Y-326959D02*
X803802Y-326934D01*
X803682Y-326834D01*
X803602Y-326659D01*
X803562Y-326459D01*
X803602Y-326259D01*
X803682Y-326084D01*
X803802Y-325984D01*
X803922Y-325959D01*
X804042Y-325984D01*
X804162Y-326084D01*
X804242Y-326259D01*
X804262Y-326459D01*
X804242Y-326659D01*
X804162Y-326834D01*
X804042Y-326934D01*
X803922Y-326959D01*
G01X805482D02*
Y-325959D01*
G01Y-326134D02*
X805402Y-326034D01*
X805282Y-325984D01*
X805142Y-325959D01*
X805002Y-326009D01*
X804882Y-326109D01*
X804802Y-326259D01*
X804762Y-326459D01*
X804802Y-326659D01*
X804882Y-326809D01*
X805002Y-326909D01*
X805142Y-326959D01*
X805282Y-326934D01*
X805402Y-326859D01*
X805482Y-326759D01*
G01X806042Y-326959D02*
Y-325959D01*
G01Y-326159D02*
X806142Y-326059D01*
X806242Y-325984D01*
X806382Y-325959D01*
X806482Y-325984D01*
X806602Y-326059D01*
G01X807882Y-325459D02*
Y-326959D01*
G01Y-326734D02*
X807802Y-326859D01*
X807682Y-326934D01*
X807542Y-326959D01*
X807382Y-326909D01*
X807262Y-326784D01*
X807182Y-326634D01*
X807162Y-326459D01*
X807182Y-326284D01*
X807262Y-326134D01*
X807382Y-326009D01*
X807542Y-325959D01*
X807682Y-325984D01*
X807782Y-326034D01*
X807882Y-326134D01*
G01X809522Y-326959D02*
Y-325459D01*
X810022D01*
X810182Y-325534D01*
X810282Y-325634D01*
X810322Y-325834D01*
X810282Y-326034D01*
X810162Y-326159D01*
X810022Y-326234D01*
X809522D01*
G01X810022D02*
X810322Y-326959D01*
G01X810822Y-326284D02*
X811462D01*
X811402Y-326109D01*
X811302Y-326009D01*
X811162Y-325959D01*
X811022Y-325984D01*
X810902Y-326059D01*
X810822Y-326234D01*
X810782Y-326384D01*
Y-326534D01*
X810822Y-326684D01*
X810922Y-326834D01*
X811042Y-326934D01*
X811182Y-326959D01*
X811322Y-326909D01*
X811462Y-326759D01*
G01X811962Y-325959D02*
X812322Y-326959D01*
X812682Y-325959D01*
G01X813522Y-327009D02*
X813482Y-326984D01*
Y-326934D01*
X813522Y-326909D01*
X813562Y-326934D01*
Y-326984D01*
X813522Y-327009D01*
G01X814682Y-326959D02*
X814722Y-326634D01*
X814782Y-326359D01*
X814862Y-326109D01*
X814962Y-325834D01*
X815122Y-325459D01*
X814322D01*
G01X816082Y-326159D02*
X816162Y-326084D01*
X816222Y-325959D01*
X816262Y-325784D01*
X816222Y-325634D01*
X816142Y-325534D01*
X816002Y-325459D01*
X815462D01*
Y-326959D01*
X816122D01*
X816262Y-326859D01*
X816342Y-326709D01*
X816382Y-326534D01*
X816342Y-326359D01*
X816222Y-326209D01*
X816082Y-326159D01*
X815462D01*
G01X-320500Y-470483D02*
Y2626000D01*
X2967000D01*
Y-470483D01*
X-320500D01*
G01X331395Y-304184D02*
X330925Y-303869D01*
X330377Y-303659D01*
X329750D01*
X329045Y-303974D01*
X328497Y-304499D01*
X328105Y-305129D01*
X327792Y-306179D01*
X327714Y-307124D01*
X327870Y-308069D01*
X328105Y-308699D01*
X328575Y-309329D01*
X329124Y-309749D01*
X329672Y-309959D01*
X330220D01*
X330769Y-309749D01*
X331239Y-309434D01*
X331630Y-309014D01*
G01X335032Y-303659D02*
X336912D01*
G01X335972D02*
Y-309959D01*
G01X335032D02*
X336912D01*
G01X342272Y-303659D02*
Y-309959D01*
G01X340470Y-303659D02*
X344074D01*
G01X348572Y-309959D02*
Y-307124D01*
X347005Y-303659D01*
G01X350139D02*
X348572Y-307124D01*
G01X359449Y-308699D02*
X359919Y-309434D01*
X360545Y-309854D01*
X361250Y-309959D01*
X361877Y-309854D01*
X362504Y-309329D01*
X362895Y-308699D01*
X362974Y-308069D01*
X362817Y-307334D01*
X362269Y-306809D01*
X361720Y-306599D01*
X361015D01*
G01X361720D02*
X362190Y-306284D01*
X362582Y-305759D01*
X362739Y-305129D01*
X362582Y-304499D01*
X362190Y-303974D01*
X361485Y-303659D01*
X360780Y-303764D01*
X360075Y-304184D01*
G01X365749Y-308699D02*
X366219Y-309434D01*
X366845Y-309854D01*
X367550Y-309959D01*
X368177Y-309854D01*
X368804Y-309329D01*
X369195Y-308699D01*
X369274Y-308069D01*
X369117Y-307334D01*
X368569Y-306809D01*
X368020Y-306599D01*
X367315D01*
G01X368020D02*
X368490Y-306284D01*
X368882Y-305759D01*
X369039Y-305129D01*
X368882Y-304499D01*
X368490Y-303974D01*
X367785Y-303659D01*
X367080Y-303764D01*
X366375Y-304184D01*
G01X372049Y-308699D02*
X372519Y-309434D01*
X373145Y-309854D01*
X373850Y-309959D01*
X374477Y-309854D01*
X375104Y-309329D01*
X375495Y-308699D01*
X375574Y-308069D01*
X375417Y-307334D01*
X374869Y-306809D01*
X374320Y-306599D01*
X373615D01*
G01X374320D02*
X374790Y-306284D01*
X375182Y-305759D01*
X375339Y-305129D01*
X375182Y-304499D01*
X374790Y-303974D01*
X374085Y-303659D01*
X373380Y-303764D01*
X372675Y-304184D01*
G01X379915Y-309959D02*
X380072Y-308594D01*
X380307Y-307439D01*
X380620Y-306389D01*
X381012Y-305234D01*
X381639Y-303659D01*
X378505D01*
G01X386215Y-309959D02*
X386372Y-308594D01*
X386607Y-307439D01*
X386920Y-306389D01*
X387312Y-305234D01*
X387939Y-303659D01*
X384805D01*
G01X392515Y-311114D02*
X392829Y-309749D01*
G01X398972Y-303659D02*
Y-309959D01*
G01X397170Y-303659D02*
X400774D01*
G01X403314Y-309959D02*
X405272Y-303659D01*
X407230Y-309959D01*
G01X406525Y-307754D02*
X404019D01*
G01X410632Y-303659D02*
X412512D01*
G01X411572D02*
Y-309959D01*
G01X410632D02*
X412512D01*
G01X415522Y-303659D02*
X416619Y-309959D01*
X417872Y-303659D01*
X419125Y-309959D01*
X420222Y-303659D01*
G01X422214Y-309959D02*
X424172Y-303659D01*
X426130Y-309959D01*
G01X425425Y-307754D02*
X422919D01*
G01X428670Y-309959D02*
Y-303659D01*
X432274Y-309959D01*
Y-303659D01*
G01X442680Y-312059D02*
X441897Y-311009D01*
X441505Y-309959D01*
Y-305759D01*
X441897Y-304709D01*
X442680Y-303659D01*
G01X454105Y-309959D02*
Y-303659D01*
X456064D01*
X456690Y-303974D01*
X457082Y-304394D01*
X457239Y-305234D01*
X457082Y-306074D01*
X456612Y-306599D01*
X456064Y-306914D01*
X454105D01*
G01X456064D02*
X457239Y-309959D01*
G01X461972Y-310169D02*
X461815Y-310064D01*
Y-309854D01*
X461972Y-309749D01*
X462129Y-309854D01*
Y-310064D01*
X461972Y-310169D01*
G01X468272Y-309959D02*
X467645Y-309854D01*
X467097Y-309434D01*
X466627Y-308804D01*
X466314Y-308069D01*
X466157Y-307229D01*
Y-306389D01*
X466314Y-305549D01*
X466627Y-304814D01*
X467097Y-304184D01*
X467645Y-303764D01*
X468272Y-303659D01*
X468899Y-303764D01*
X469447Y-304184D01*
X469917Y-304814D01*
X470230Y-305549D01*
X470387Y-306389D01*
Y-307229D01*
X470230Y-308069D01*
X469917Y-308804D01*
X469447Y-309434D01*
X468899Y-309854D01*
X468272Y-309959D01*
G01X474572Y-310169D02*
X474415Y-310064D01*
Y-309854D01*
X474572Y-309749D01*
X474729Y-309854D01*
Y-310064D01*
X474572Y-310169D01*
G01X482595Y-304184D02*
X482125Y-303869D01*
X481577Y-303659D01*
X480950D01*
X480245Y-303974D01*
X479697Y-304499D01*
X479305Y-305129D01*
X478992Y-306179D01*
X478914Y-307124D01*
X479070Y-308069D01*
X479305Y-308699D01*
X479775Y-309329D01*
X480324Y-309749D01*
X480872Y-309959D01*
X481420D01*
X481969Y-309749D01*
X482439Y-309434D01*
X482830Y-309014D01*
G01X487172Y-310169D02*
X487015Y-310064D01*
Y-309854D01*
X487172Y-309749D01*
X487329Y-309854D01*
Y-310064D01*
X487172Y-310169D01*
G01X493864Y-312059D02*
X494647Y-311009D01*
X495039Y-309959D01*
Y-305759D01*
X494647Y-304709D01*
X493864Y-303659D01*
G01X330142Y-296809D02*
X331709D01*
Y-298699D01*
X331239Y-299329D01*
X330690Y-299749D01*
X329907Y-299959D01*
X329124Y-299749D01*
X328575Y-299329D01*
X328105Y-298699D01*
X327792Y-297964D01*
X327635Y-297124D01*
Y-296389D01*
X327792Y-295759D01*
X328105Y-295024D01*
X328575Y-294394D01*
X329045Y-293974D01*
X329672Y-293659D01*
X330220D01*
X330847Y-293869D01*
X331317Y-294289D01*
G01X334249Y-293659D02*
Y-298174D01*
X334562Y-299119D01*
X335189Y-299749D01*
X335972Y-299959D01*
X336755Y-299749D01*
X337382Y-299119D01*
X337695Y-298174D01*
Y-293659D01*
G01X341332D02*
X343212D01*
G01X342272D02*
Y-299959D01*
G01X341332D02*
X343212D01*
G01X346927Y-299119D02*
X347554Y-299644D01*
X348259Y-299959D01*
X348885D01*
X349512Y-299644D01*
X349982Y-299119D01*
X350217Y-298384D01*
X350060Y-297649D01*
X349669Y-297019D01*
X348964Y-296599D01*
X348024Y-296389D01*
X347475Y-295969D01*
X347240Y-295234D01*
X347397Y-294499D01*
X347789Y-293974D01*
X348337Y-293659D01*
X348885D01*
X349434Y-293869D01*
X349904Y-294394D01*
G01X353227Y-299959D02*
Y-293659D01*
G01X356517D02*
Y-299959D01*
G01Y-296809D02*
X353227D01*
G01X359214Y-299959D02*
X361172Y-293659D01*
X363130Y-299959D01*
G01X362425Y-297754D02*
X359919D01*
G01X365670Y-299959D02*
Y-293659D01*
X369274Y-299959D01*
Y-293659D01*
G01X378349Y-299959D02*
Y-293659D01*
X379915D01*
X380542Y-293974D01*
X381012Y-294394D01*
X381404Y-295024D01*
X381717Y-295759D01*
X381795Y-296809D01*
X381717Y-297859D01*
X381404Y-298594D01*
X381012Y-299224D01*
X380542Y-299644D01*
X379915Y-299959D01*
X378349D01*
G01X385432Y-293659D02*
X387312D01*
G01X386372D02*
Y-299959D01*
G01X385432D02*
X387312D01*
G01X391027Y-299119D02*
X391654Y-299644D01*
X392359Y-299959D01*
X392985D01*
X393612Y-299644D01*
X394082Y-299119D01*
X394317Y-298384D01*
X394160Y-297649D01*
X393769Y-297019D01*
X393064Y-296599D01*
X392124Y-296389D01*
X391575Y-295969D01*
X391340Y-295234D01*
X391497Y-294499D01*
X391889Y-293974D01*
X392437Y-293659D01*
X392985D01*
X393534Y-293869D01*
X394004Y-294394D01*
G01X398972Y-293659D02*
Y-299959D01*
G01X397170Y-293659D02*
X400774D01*
G01X405272Y-300169D02*
X405115Y-300064D01*
Y-299854D01*
X405272Y-299749D01*
X405429Y-299854D01*
Y-300064D01*
X405272Y-300169D01*
G01X411415Y-301114D02*
X411729Y-299749D01*
G01X417872Y-293659D02*
Y-299959D01*
G01X416070Y-293659D02*
X419674D01*
G01X422214Y-299959D02*
X424172Y-293659D01*
X426130Y-299959D01*
G01X425425Y-297754D02*
X422919D01*
G01X430472Y-299959D02*
X429845Y-299854D01*
X429297Y-299434D01*
X428827Y-298804D01*
X428514Y-298069D01*
X428357Y-297229D01*
Y-296389D01*
X428514Y-295549D01*
X428827Y-294814D01*
X429297Y-294184D01*
X429845Y-293764D01*
X430472Y-293659D01*
X431099Y-293764D01*
X431647Y-294184D01*
X432117Y-294814D01*
X432430Y-295549D01*
X432587Y-296389D01*
Y-297229D01*
X432430Y-298069D01*
X432117Y-298804D01*
X431647Y-299434D01*
X431099Y-299854D01*
X430472Y-299959D01*
G01X436772D02*
Y-297124D01*
X435205Y-293659D01*
G01X438339D02*
X436772Y-297124D01*
G01X441349Y-293659D02*
Y-298174D01*
X441662Y-299119D01*
X442289Y-299749D01*
X443072Y-299959D01*
X443855Y-299749D01*
X444482Y-299119D01*
X444795Y-298174D01*
Y-293659D01*
G01X447414Y-299959D02*
X449372Y-293659D01*
X451330Y-299959D01*
G01X450625Y-297754D02*
X448119D01*
G01X453870Y-299959D02*
Y-293659D01*
X457474Y-299959D01*
Y-293659D01*
G01X327870Y-289959D02*
Y-283659D01*
X331474Y-289959D01*
Y-283659D01*
G01X335972Y-289959D02*
X335345Y-289854D01*
X334797Y-289434D01*
X334327Y-288804D01*
X334014Y-288069D01*
X333857Y-287229D01*
Y-286389D01*
X334014Y-285549D01*
X334327Y-284814D01*
X334797Y-284184D01*
X335345Y-283764D01*
X335972Y-283659D01*
X336599Y-283764D01*
X337147Y-284184D01*
X337617Y-284814D01*
X337930Y-285549D01*
X338087Y-286389D01*
Y-287229D01*
X337930Y-288069D01*
X337617Y-288804D01*
X337147Y-289434D01*
X336599Y-289854D01*
X335972Y-289959D01*
G01X342272Y-290169D02*
X342115Y-290064D01*
Y-289854D01*
X342272Y-289749D01*
X342429Y-289854D01*
Y-290064D01*
X342272Y-290169D01*
G01X347084Y-284709D02*
X347554Y-284079D01*
X348102Y-283764D01*
X348729Y-283659D01*
X349512Y-283869D01*
X350060Y-284394D01*
X350217Y-285024D01*
X350139Y-285654D01*
X349825Y-286179D01*
X348259Y-287229D01*
X347554Y-287964D01*
X347084Y-289014D01*
X346927Y-289959D01*
X350217D01*
G01X354872D02*
Y-283659D01*
X353932Y-284919D01*
G01Y-289959D02*
X355812D01*
G01X361172D02*
Y-283659D01*
X360232Y-284919D01*
G01Y-289959D02*
X362112D01*
G01X367315Y-291114D02*
X367629Y-289749D01*
G01X371422Y-283659D02*
X372519Y-289959D01*
X373772Y-283659D01*
X375025Y-289959D01*
X376122Y-283659D01*
G01X381639Y-289959D02*
X378505D01*
Y-283659D01*
X381639D01*
G01X380385Y-286704D02*
X378505D01*
G01X384570Y-289959D02*
Y-283659D01*
X388174Y-289959D01*
Y-283659D01*
G01X391027Y-289959D02*
Y-283659D01*
G01X394317D02*
Y-289959D01*
G01Y-286809D02*
X391027D01*
G01X397249Y-283659D02*
Y-288174D01*
X397562Y-289119D01*
X398189Y-289749D01*
X398972Y-289959D01*
X399755Y-289749D01*
X400382Y-289119D01*
X400695Y-288174D01*
Y-283659D01*
G01X403314Y-289959D02*
X405272Y-283659D01*
X407230Y-289959D01*
G01X406525Y-287754D02*
X404019D01*
G01X416384Y-284709D02*
X416854Y-284079D01*
X417402Y-283764D01*
X418029Y-283659D01*
X418812Y-283869D01*
X419360Y-284394D01*
X419517Y-285024D01*
X419439Y-285654D01*
X419125Y-286179D01*
X417559Y-287229D01*
X416854Y-287964D01*
X416384Y-289014D01*
X416227Y-289959D01*
X419517D01*
G01X422370D02*
Y-283659D01*
X425974Y-289959D01*
Y-283659D01*
G01X428749Y-289959D02*
Y-283659D01*
X430315D01*
X430942Y-283974D01*
X431412Y-284394D01*
X431804Y-285024D01*
X432117Y-285759D01*
X432195Y-286809D01*
X432117Y-287859D01*
X431804Y-288594D01*
X431412Y-289224D01*
X430942Y-289644D01*
X430315Y-289959D01*
X428749D01*
G01X441505D02*
Y-283659D01*
X443464D01*
X444090Y-283974D01*
X444482Y-284394D01*
X444639Y-285234D01*
X444482Y-286074D01*
X444012Y-286599D01*
X443464Y-286914D01*
X441505D01*
G01X443464D02*
X444639Y-289959D01*
G01X447649D02*
Y-283659D01*
X449215D01*
X449842Y-283974D01*
X450312Y-284394D01*
X450704Y-285024D01*
X451017Y-285759D01*
X451095Y-286809D01*
X451017Y-287859D01*
X450704Y-288594D01*
X450312Y-289224D01*
X449842Y-289644D01*
X449215Y-289959D01*
X447649D01*
G01X455672Y-290169D02*
X455515Y-290064D01*
Y-289854D01*
X455672Y-289749D01*
X455829Y-289854D01*
Y-290064D01*
X455672Y-290169D01*
G01X351972Y-279259D02*
X349452Y-278842D01*
X347247Y-277176D01*
X345357Y-274676D01*
X344097Y-271759D01*
X343467Y-268426D01*
Y-265092D01*
X344097Y-261759D01*
X345357Y-258842D01*
X347247Y-256343D01*
X349452Y-254676D01*
X351972Y-254259D01*
X354492Y-254676D01*
X356697Y-256343D01*
X358587Y-258842D01*
X359847Y-261759D01*
X360477Y-265092D01*
Y-268426D01*
X359847Y-271759D01*
X358587Y-274676D01*
X356697Y-277176D01*
X354492Y-278842D01*
X351972Y-279259D01*
G01X354492Y-272592D02*
X358272Y-279259D01*
G01X371817Y-262593D02*
Y-274259D01*
X373077Y-277176D01*
X374967Y-278842D01*
X377172Y-279259D01*
X379377Y-278842D01*
X381267Y-277176D01*
X382527Y-274259D01*
G01Y-279259D02*
Y-262593D01*
G01X408042Y-279259D02*
Y-262593D01*
G01Y-265509D02*
X406782Y-263843D01*
X404892Y-263009D01*
X402687Y-262593D01*
X400482Y-263426D01*
X398592Y-265092D01*
X397332Y-267593D01*
X396702Y-270926D01*
X397332Y-274259D01*
X398592Y-276760D01*
X400482Y-278426D01*
X402687Y-279259D01*
X404892Y-278842D01*
X406782Y-277593D01*
X408042Y-275926D01*
G01X422217Y-279259D02*
Y-262593D01*
G01Y-266759D02*
X423477Y-264676D01*
X425367Y-263009D01*
X427887Y-262593D01*
X430092Y-263009D01*
X431982Y-264676D01*
X432927Y-267593D01*
Y-279259D01*
G01X452772Y-254259D02*
Y-279259D01*
G01X448362Y-262593D02*
X457182D01*
G01X483642Y-279259D02*
Y-262593D01*
G01Y-265509D02*
X482382Y-263843D01*
X480492Y-263009D01*
X478287Y-262593D01*
X476082Y-263426D01*
X474192Y-265092D01*
X472932Y-267593D01*
X472302Y-270926D01*
X472932Y-274259D01*
X474192Y-276760D01*
X476082Y-278426D01*
X478287Y-279259D01*
X480492Y-278842D01*
X482382Y-277593D01*
X483642Y-275926D01*
G01X534822Y-291959D02*
Y-283959D01*
X537222D01*
X538022Y-284359D01*
X538622Y-285292D01*
X538822Y-286359D01*
X538622Y-287426D01*
X538122Y-288226D01*
X537222Y-288626D01*
X534822D01*
G01X542322Y-291959D02*
X544822Y-283959D01*
X547322Y-291959D01*
G01X546422Y-289159D02*
X543222D01*
G01X550722Y-290893D02*
X551522Y-291559D01*
X552422Y-291959D01*
X553222D01*
X554022Y-291559D01*
X554622Y-290893D01*
X554922Y-289959D01*
X554722Y-289026D01*
X554222Y-288226D01*
X553322Y-287692D01*
X552122Y-287426D01*
X551422Y-286892D01*
X551122Y-285959D01*
X551322Y-285026D01*
X551822Y-284359D01*
X552522Y-283959D01*
X553222D01*
X553922Y-284226D01*
X554522Y-284892D01*
G01X560822Y-283959D02*
Y-291959D01*
G01X558522Y-283959D02*
X563122D01*
G01X567522Y-289292D02*
X570122D01*
G01X576822Y-283959D02*
Y-291959D01*
G01X574522Y-283959D02*
X579122D01*
G01X584822Y-291959D02*
X584022Y-291826D01*
X583322Y-291292D01*
X582722Y-290492D01*
X582322Y-289559D01*
X582122Y-288492D01*
Y-287426D01*
X582322Y-286359D01*
X582722Y-285426D01*
X583322Y-284626D01*
X584022Y-284092D01*
X584822Y-283959D01*
X585622Y-284092D01*
X586322Y-284626D01*
X586922Y-285426D01*
X587322Y-286359D01*
X587522Y-287426D01*
Y-288492D01*
X587322Y-289559D01*
X586922Y-290492D01*
X586322Y-291292D01*
X585622Y-291826D01*
X584822Y-291959D01*
G01X590822D02*
Y-283959D01*
X593222D01*
X594022Y-284359D01*
X594622Y-285292D01*
X594822Y-286359D01*
X594622Y-287426D01*
X594122Y-288226D01*
X593222Y-288626D01*
X590822D01*
G01X523322Y-258959D02*
Y-266959D01*
X527322D01*
G01X535122D02*
Y-261626D01*
G01Y-262559D02*
X534722Y-262026D01*
X534122Y-261759D01*
X533422Y-261626D01*
X532722Y-261892D01*
X532122Y-262426D01*
X531722Y-263226D01*
X531522Y-264292D01*
X531722Y-265359D01*
X532122Y-266159D01*
X532722Y-266692D01*
X533422Y-266959D01*
X534122Y-266826D01*
X534722Y-266426D01*
X535122Y-265893D01*
G01X539222Y-269359D02*
X539822Y-269626D01*
X540622Y-269359D01*
X541122Y-268826D01*
X541522Y-268159D01*
X542122Y-266026D01*
X543422Y-261626D01*
G01X540222D02*
X542122Y-266026D01*
G01X547822Y-263359D02*
X551022D01*
X550722Y-262426D01*
X550222Y-261892D01*
X549522Y-261626D01*
X548822Y-261759D01*
X548222Y-262159D01*
X547822Y-263092D01*
X547622Y-263893D01*
Y-264692D01*
X547822Y-265492D01*
X548322Y-266292D01*
X548922Y-266826D01*
X549622Y-266959D01*
X550322Y-266692D01*
X551022Y-265893D01*
G01X555922Y-266959D02*
Y-261626D01*
G01Y-262692D02*
X556422Y-262159D01*
X556922Y-261759D01*
X557622Y-261626D01*
X558122Y-261759D01*
X558722Y-262159D01*
G01X542022Y-316959D02*
Y-308959D01*
X546622Y-316959D01*
Y-308959D01*
G01X552322Y-311626D02*
Y-316959D01*
G01Y-309492D02*
X552122Y-309359D01*
Y-309092D01*
X552322Y-308959D01*
X552522Y-309092D01*
Y-309359D01*
X552322Y-309492D01*
G01X558622Y-316959D02*
Y-311626D01*
G01Y-312959D02*
X559022Y-312292D01*
X559622Y-311759D01*
X560422Y-311626D01*
X561122Y-311759D01*
X561722Y-312292D01*
X562022Y-313226D01*
Y-316959D01*
G01X570122D02*
Y-311626D01*
G01Y-312559D02*
X569722Y-312026D01*
X569122Y-311759D01*
X568422Y-311626D01*
X567722Y-311892D01*
X567122Y-312426D01*
X566722Y-313226D01*
X566522Y-314292D01*
X566722Y-315359D01*
X567122Y-316159D01*
X567722Y-316692D01*
X568422Y-316959D01*
X569122Y-316826D01*
X569722Y-316426D01*
X570122Y-315893D01*
G01X649922Y-310292D02*
X650522Y-309492D01*
X651222Y-309092D01*
X652022Y-308959D01*
X653022Y-309226D01*
X653722Y-309892D01*
X653922Y-310692D01*
X653822Y-311493D01*
X653422Y-312159D01*
X651422Y-313492D01*
X650522Y-314426D01*
X649922Y-315759D01*
X649722Y-316959D01*
X653922D01*
G01X659822Y-308959D02*
X659022Y-309226D01*
X658422Y-309892D01*
X658022Y-310692D01*
X657722Y-311759D01*
X657622Y-312959D01*
X657722Y-314159D01*
X658022Y-315226D01*
X658422Y-316026D01*
X659022Y-316692D01*
X659822Y-316959D01*
X660622Y-316692D01*
X661222Y-316026D01*
X661622Y-315226D01*
X661922Y-314159D01*
X662022Y-312959D01*
X661922Y-311759D01*
X661622Y-310692D01*
X661222Y-309892D01*
X660622Y-309226D01*
X659822Y-308959D01*
G01X665922Y-310292D02*
X666522Y-309492D01*
X667222Y-309092D01*
X668022Y-308959D01*
X669022Y-309226D01*
X669722Y-309892D01*
X669922Y-310692D01*
X669822Y-311493D01*
X669422Y-312159D01*
X667422Y-313492D01*
X666522Y-314426D01*
X665922Y-315759D01*
X665722Y-316959D01*
X669922D01*
G01X673922Y-310292D02*
X674522Y-309492D01*
X675222Y-309092D01*
X676022Y-308959D01*
X677022Y-309226D01*
X677722Y-309892D01*
X677922Y-310692D01*
X677822Y-311493D01*
X677422Y-312159D01*
X675422Y-313492D01*
X674522Y-314426D01*
X673922Y-315759D01*
X673722Y-316959D01*
X677922D01*
G01X682022Y-317226D02*
X685622Y-308959D01*
G01X691822Y-316959D02*
Y-308959D01*
X690622Y-310559D01*
G01Y-316959D02*
X693022D01*
G01X697922Y-310292D02*
X698522Y-309492D01*
X699222Y-309092D01*
X700022Y-308959D01*
X701022Y-309226D01*
X701722Y-309892D01*
X701922Y-310692D01*
X701822Y-311493D01*
X701422Y-312159D01*
X699422Y-313492D01*
X698522Y-314426D01*
X697922Y-315759D01*
X697722Y-316959D01*
X701922D01*
G01X706022Y-317226D02*
X709622Y-308959D01*
G01X715822D02*
X715022Y-309226D01*
X714422Y-309892D01*
X714022Y-310692D01*
X713722Y-311759D01*
X713622Y-312959D01*
X713722Y-314159D01*
X714022Y-315226D01*
X714422Y-316026D01*
X715022Y-316692D01*
X715822Y-316959D01*
X716622Y-316692D01*
X717222Y-316026D01*
X717622Y-315226D01*
X717922Y-314159D01*
X718022Y-312959D01*
X717922Y-311759D01*
X717622Y-310692D01*
X717222Y-309892D01*
X716622Y-309226D01*
X715822Y-308959D01*
G01X722122Y-316026D02*
X722822Y-316692D01*
X723622Y-316959D01*
X724422Y-316692D01*
X725122Y-315893D01*
X725622Y-314692D01*
X725822Y-313492D01*
Y-312026D01*
X725622Y-310826D01*
X725122Y-309759D01*
X724522Y-309226D01*
X723822Y-308959D01*
X723022Y-309226D01*
X722422Y-309759D01*
X722022Y-310559D01*
X721822Y-311626D01*
X722022Y-312559D01*
X722522Y-313492D01*
X723122Y-314026D01*
X723822Y-314159D01*
X724622Y-313893D01*
X725222Y-313226D01*
X725822Y-312026D01*
G01X649622Y-291959D02*
Y-283959D01*
X651622D01*
X652422Y-284359D01*
X653022Y-284892D01*
X653522Y-285692D01*
X653922Y-286626D01*
X654022Y-287959D01*
X653922Y-289292D01*
X653522Y-290226D01*
X653022Y-291026D01*
X652422Y-291559D01*
X651622Y-291959D01*
X649622D01*
G01X657322D02*
X659822Y-283959D01*
X662322Y-291959D01*
G01X661422Y-289159D02*
X658222D01*
G01X667822Y-283959D02*
X667022Y-284226D01*
X666422Y-284892D01*
X666022Y-285692D01*
X665722Y-286759D01*
X665622Y-287959D01*
X665722Y-289159D01*
X666022Y-290226D01*
X666422Y-291026D01*
X667022Y-291692D01*
X667822Y-291959D01*
X668622Y-291692D01*
X669222Y-291026D01*
X669622Y-290226D01*
X669922Y-289159D01*
X670022Y-287959D01*
X669922Y-286759D01*
X669622Y-285692D01*
X669222Y-284892D01*
X668622Y-284226D01*
X667822Y-283959D01*
G01X673922Y-291959D02*
Y-283959D01*
X677722D01*
G01X676322Y-287826D02*
X673922D01*
G01X683822Y-283959D02*
X683022Y-284226D01*
X682422Y-284892D01*
X682022Y-285692D01*
X681722Y-286759D01*
X681622Y-287959D01*
X681722Y-289159D01*
X682022Y-290226D01*
X682422Y-291026D01*
X683022Y-291692D01*
X683822Y-291959D01*
X684622Y-291692D01*
X685222Y-291026D01*
X685622Y-290226D01*
X685922Y-289159D01*
X686022Y-287959D01*
X685922Y-286759D01*
X685622Y-285692D01*
X685222Y-284892D01*
X684622Y-284226D01*
X683822Y-283959D01*
G01X691822D02*
Y-291959D01*
G01X689522Y-283959D02*
X694122D01*
G01X697922Y-291959D02*
Y-283959D01*
X701722D01*
G01X700322Y-287826D02*
X697922D01*
G01X708622Y-287692D02*
X709022Y-287292D01*
X709322Y-286626D01*
X709522Y-285692D01*
X709322Y-284892D01*
X708922Y-284359D01*
X708222Y-283959D01*
X705522D01*
Y-291959D01*
X708822D01*
X709522Y-291426D01*
X709922Y-290626D01*
X710122Y-289692D01*
X709922Y-288759D01*
X709322Y-287959D01*
X708622Y-287692D01*
X705522D01*
G01X713922Y-288626D02*
X714622Y-287692D01*
X715222Y-287159D01*
X716022Y-286892D01*
X716722Y-287159D01*
X717222Y-287692D01*
X717622Y-288492D01*
X717722Y-289426D01*
X717622Y-290226D01*
X717222Y-291026D01*
X716622Y-291692D01*
X715922Y-291959D01*
X715122Y-291692D01*
X714422Y-290893D01*
X714022Y-289692D01*
X713922Y-288359D01*
X714122Y-286626D01*
X714422Y-285692D01*
X714922Y-284759D01*
X715622Y-284092D01*
X716322Y-283959D01*
X717022Y-284226D01*
X717522Y-284892D01*
G01X721622Y-291959D02*
Y-283959D01*
X723622D01*
X724422Y-284359D01*
X725022Y-284892D01*
X725522Y-285692D01*
X725922Y-286626D01*
X726022Y-287959D01*
X725922Y-289292D01*
X725522Y-290226D01*
X725022Y-291026D01*
X724422Y-291559D01*
X723622Y-291959D01*
X721622D01*
G01X731822Y-283959D02*
X731022Y-284226D01*
X730422Y-284892D01*
X730022Y-285692D01*
X729722Y-286759D01*
X729622Y-287959D01*
X729722Y-289159D01*
X730022Y-290226D01*
X730422Y-291026D01*
X731022Y-291692D01*
X731822Y-291959D01*
X732622Y-291692D01*
X733222Y-291026D01*
X733622Y-290226D01*
X733922Y-289159D01*
X734022Y-287959D01*
X733922Y-286759D01*
X733622Y-285692D01*
X733222Y-284892D01*
X732622Y-284226D01*
X731822Y-283959D01*
G01X649862Y-270000D02*
Y-263700D01*
X652838D01*
G01X651742Y-266745D02*
X649862D01*
G01X657650Y-263700D02*
X657023Y-263910D01*
X656553Y-264435D01*
X656240Y-265065D01*
X656005Y-265905D01*
X655927Y-266850D01*
X656005Y-267795D01*
X656240Y-268635D01*
X656553Y-269265D01*
X657023Y-269790D01*
X657650Y-270000D01*
X658277Y-269790D01*
X658747Y-269265D01*
X659060Y-268635D01*
X659295Y-267795D01*
X659373Y-266850D01*
X659295Y-265905D01*
X659060Y-265065D01*
X658747Y-264435D01*
X658277Y-263910D01*
X657650Y-263700D01*
G01X663950D02*
Y-270000D01*
G01X662148Y-263700D02*
X665752D01*
G01X667900Y-272100D02*
X672600D01*
G01X674983Y-270000D02*
Y-263700D01*
X676863D01*
X677490Y-264015D01*
X677960Y-264750D01*
X678117Y-265590D01*
X677960Y-266430D01*
X677568Y-267060D01*
X676863Y-267375D01*
X674983D01*
G01X684573Y-264225D02*
X684103Y-263910D01*
X683555Y-263700D01*
X682928D01*
X682223Y-264015D01*
X681675Y-264540D01*
X681283Y-265170D01*
X680970Y-266220D01*
X680892Y-267165D01*
X681048Y-268110D01*
X681283Y-268740D01*
X681753Y-269370D01*
X682302Y-269790D01*
X682850Y-270000D01*
X683398D01*
X683947Y-269790D01*
X684417Y-269475D01*
X684808Y-269055D01*
G01X689777Y-266640D02*
X690090Y-266325D01*
X690325Y-265800D01*
X690482Y-265065D01*
X690325Y-264435D01*
X690012Y-264015D01*
X689463Y-263700D01*
X687348D01*
Y-270000D01*
X689933D01*
X690482Y-269580D01*
X690795Y-268950D01*
X690952Y-268215D01*
X690795Y-267480D01*
X690325Y-266850D01*
X689777Y-266640D01*
X687348D01*
G01X693100Y-272100D02*
X697800D01*
G01X700262Y-270000D02*
Y-263700D01*
X703238D01*
G01X702142Y-266745D02*
X700262D01*
G01X706092Y-270000D02*
X708050Y-263700D01*
X710008Y-270000D01*
G01X709303Y-267795D02*
X706797D01*
G01X712548Y-270000D02*
Y-263700D01*
X716152Y-270000D01*
Y-263700D01*
G01X718300Y-272100D02*
X723000D01*
G01X727577Y-266640D02*
X727890Y-266325D01*
X728125Y-265800D01*
X728282Y-265065D01*
X728125Y-264435D01*
X727812Y-264015D01*
X727263Y-263700D01*
X725148D01*
Y-270000D01*
X727733D01*
X728282Y-269580D01*
X728595Y-268950D01*
X728752Y-268215D01*
X728595Y-267480D01*
X728125Y-266850D01*
X727577Y-266640D01*
X725148D01*
G01X733250Y-270000D02*
X732623Y-269895D01*
X732075Y-269475D01*
X731605Y-268845D01*
X731292Y-268110D01*
X731135Y-267270D01*
Y-266430D01*
X731292Y-265590D01*
X731605Y-264855D01*
X732075Y-264225D01*
X732623Y-263805D01*
X733250Y-263700D01*
X733877Y-263805D01*
X734425Y-264225D01*
X734895Y-264855D01*
X735208Y-265590D01*
X735365Y-266430D01*
Y-267270D01*
X735208Y-268110D01*
X734895Y-268845D01*
X734425Y-269475D01*
X733877Y-269895D01*
X733250Y-270000D01*
G01X737592D02*
X739550Y-263700D01*
X741508Y-270000D01*
G01X740803Y-267795D02*
X738297D01*
G01X744283Y-270000D02*
Y-263700D01*
X746242D01*
X746868Y-264015D01*
X747260Y-264435D01*
X747417Y-265275D01*
X747260Y-266115D01*
X746790Y-266640D01*
X746242Y-266955D01*
X744283D01*
G01X746242D02*
X747417Y-270000D01*
G01X750427D02*
Y-263700D01*
X751993D01*
X752620Y-264015D01*
X753090Y-264435D01*
X753482Y-265065D01*
X753795Y-265800D01*
X753873Y-266850D01*
X753795Y-267900D01*
X753482Y-268635D01*
X753090Y-269265D01*
X752620Y-269685D01*
X751993Y-270000D01*
X750427D01*
G01X756100Y-272100D02*
X760800D01*
G01X762713Y-270000D02*
Y-263700D01*
X764750Y-268950D01*
X766787Y-263700D01*
Y-270000D01*
G01X769483D02*
Y-263700D01*
X771363D01*
X771990Y-264015D01*
X772460Y-264750D01*
X772617Y-265590D01*
X772460Y-266430D01*
X772068Y-267060D01*
X771363Y-267375D01*
X769483D01*
G01X775627Y-269055D02*
X776097Y-269580D01*
X776645Y-269895D01*
X777350Y-270000D01*
X778055Y-269790D01*
X778603Y-269370D01*
X778995Y-268635D01*
X779073Y-267795D01*
X778917Y-266955D01*
X778525Y-266430D01*
X777977Y-266010D01*
X777428Y-265905D01*
X776880Y-266010D01*
X776175Y-266430D01*
X776410Y-263700D01*
X778525D01*
G01X783650D02*
X783023Y-263910D01*
X782553Y-264435D01*
X782240Y-265065D01*
X782005Y-265905D01*
X781927Y-266850D01*
X782005Y-267795D01*
X782240Y-268635D01*
X782553Y-269265D01*
X783023Y-269790D01*
X783650Y-270000D01*
X784277Y-269790D01*
X784747Y-269265D01*
X785060Y-268635D01*
X785295Y-267795D01*
X785373Y-266850D01*
X785295Y-265905D01*
X785060Y-265065D01*
X784747Y-264435D01*
X784277Y-263910D01*
X783650Y-263700D01*
G01X790890Y-270000D02*
Y-263700D01*
X787992Y-268215D01*
X791908D01*
G01X796250Y-270000D02*
X796798Y-269895D01*
X797425Y-269580D01*
X797817Y-269055D01*
X797973Y-268320D01*
X797817Y-267585D01*
X797347Y-266955D01*
X796642Y-266640D01*
X795858D01*
X795388Y-266430D01*
X794997Y-265905D01*
X794840Y-265170D01*
X795075Y-264435D01*
X795623Y-263910D01*
X796250Y-263700D01*
X796877Y-263910D01*
X797425Y-264435D01*
X797660Y-265170D01*
X797503Y-265905D01*
X797112Y-266430D01*
X796642Y-266640D01*
X795858D01*
X795153Y-266955D01*
X794683Y-267585D01*
X794527Y-268320D01*
X794683Y-269055D01*
X795075Y-269580D01*
X795702Y-269895D01*
X796250Y-270000D01*
G01X738322Y-319959D02*
Y-311959D01*
X737122Y-313559D01*
G01Y-319959D02*
X739522D01*
G01X744422Y-316626D02*
X745122Y-315692D01*
X745722Y-315159D01*
X746522Y-314892D01*
X747222Y-315159D01*
X747722Y-315692D01*
X748122Y-316492D01*
X748222Y-317426D01*
X748122Y-318226D01*
X747722Y-319026D01*
X747122Y-319692D01*
X746422Y-319959D01*
X745622Y-319692D01*
X744922Y-318893D01*
X744522Y-317692D01*
X744422Y-316359D01*
X744622Y-314626D01*
X744922Y-313692D01*
X745422Y-312759D01*
X746122Y-312092D01*
X746822Y-311959D01*
X747522Y-312226D01*
X748022Y-312892D01*
G01X754322Y-320226D02*
X754122Y-320092D01*
Y-319826D01*
X754322Y-319692D01*
X754522Y-319826D01*
Y-320092D01*
X754322Y-320226D01*
G01X760422Y-316626D02*
X761122Y-315692D01*
X761722Y-315159D01*
X762522Y-314892D01*
X763222Y-315159D01*
X763722Y-315692D01*
X764122Y-316492D01*
X764222Y-317426D01*
X764122Y-318226D01*
X763722Y-319026D01*
X763122Y-319692D01*
X762422Y-319959D01*
X761622Y-319692D01*
X760922Y-318893D01*
X760522Y-317692D01*
X760422Y-316359D01*
X760622Y-314626D01*
X760922Y-313692D01*
X761422Y-312759D01*
X762122Y-312092D01*
X762822Y-311959D01*
X763522Y-312226D01*
X764022Y-312892D01*
G01X783322Y-319959D02*
Y-311959D01*
X782122Y-313559D01*
G01Y-319959D02*
X784522D01*
G01X791122D02*
X791322Y-318226D01*
X791622Y-316759D01*
X792022Y-315426D01*
X792522Y-313959D01*
X793322Y-311959D01*
X789322D01*
G01X799322Y-320226D02*
X799122Y-320092D01*
Y-319826D01*
X799322Y-319692D01*
X799522Y-319826D01*
Y-320092D01*
X799322Y-320226D01*
G01X805422Y-313292D02*
X806022Y-312492D01*
X806722Y-312092D01*
X807522Y-311959D01*
X808522Y-312226D01*
X809222Y-312892D01*
X809422Y-313692D01*
X809322Y-314493D01*
X808922Y-315159D01*
X806922Y-316492D01*
X806022Y-317426D01*
X805422Y-318759D01*
X805222Y-319959D01*
X809422D01*
G01X803122Y-294959D02*
Y-286959D01*
X805122D01*
X805922Y-287359D01*
X806522Y-287892D01*
X807022Y-288692D01*
X807422Y-289626D01*
X807522Y-290959D01*
X807422Y-292292D01*
X807022Y-293226D01*
X806522Y-294026D01*
X805922Y-294559D01*
X805122Y-294959D01*
X803122D01*
G54D29*
X29000Y694425D03*
Y696984D03*
Y699543D03*
Y702102D03*
Y704661D03*
Y707220D03*
Y709780D03*
Y712339D03*
Y714898D03*
Y717457D03*
Y720016D03*
Y722575D03*
X52000Y709780D03*
Y707220D03*
Y704661D03*
Y702102D03*
Y699543D03*
Y696984D03*
Y694425D03*
Y722575D03*
Y720016D03*
Y717457D03*
Y714898D03*
Y712339D03*
X131500Y661425D03*
Y663984D03*
Y666543D03*
Y669102D03*
Y671661D03*
Y674220D03*
Y676780D03*
Y679339D03*
Y681898D03*
Y684457D03*
Y687016D03*
Y689575D03*
X131000Y707323D03*
Y709882D03*
Y712441D03*
Y715000D03*
Y717559D03*
Y720118D03*
Y722677D03*
X131500Y738323D03*
Y740882D03*
Y743441D03*
Y746000D03*
Y748559D03*
Y751118D03*
Y753677D03*
X154500Y663984D03*
Y661425D03*
Y687016D03*
Y684457D03*
Y681898D03*
Y679339D03*
Y676780D03*
Y674220D03*
Y671661D03*
Y669102D03*
Y666543D03*
Y689575D03*
X154000Y709882D03*
Y707323D03*
Y722677D03*
Y720118D03*
Y717559D03*
Y715000D03*
Y712441D03*
X154500Y753677D03*
Y751118D03*
Y748559D03*
Y746000D03*
Y743441D03*
Y740882D03*
Y738323D03*
G54D38*
X77776Y500626D03*
Y516374D03*
X87224Y500626D03*
X85650D03*
X84075D03*
X82500D03*
X80925D03*
X79350D03*
Y516374D03*
X80925D03*
X82500D03*
X84075D03*
X85650D03*
X87224D03*
X124000Y500626D03*
X122425D03*
X120850D03*
X119276D03*
Y516374D03*
X120850D03*
X122425D03*
X124000D03*
X128724Y500626D03*
X127150D03*
X125575D03*
Y516374D03*
X127150D03*
X128724D03*
G54D39*
X82500Y508500D03*
X124000D03*
M02*
